G04 ================== begin FILE IDENTIFICATION RECORD ==================*
G04 Layout Name:  9049_F0T_FAN_BOARD_MP5048_D_v02_20221209_0830.brd*
G04 Film Name:    sst.art*
G04 File Format:  Gerber RS274X*
G04 File Origin:  Cadence Allegro 17.2-S081*
G04 Origin Date:  Mon Dec 12 15:05:05 2022*
G04 *
G04 Layer:  DRAWING FORMAT/TITLE_BLOCK_A*
G04 Layer:  BOARD GEOMETRY/DESIGN_OUTLINE*
G04 Layer:  BOARD GEOMETRY/CUTOUT*
G04 Layer:  DRAWING FORMAT/TITLE_BLOCK*
G04 Layer:  MANUFACTURING/TP_TEXT_TOP*
G04 Layer:  REF DES/SILKSCREEN_TOP*
G04 Layer:  PACKAGE GEOMETRY/SILKSCREEN_TOP*
G04 Layer:  MANUFACTURING/PHOTOPLOT_OUTLINE*
G04 Layer:  DRAWING FORMAT/TITLE_DATA_SST*
G04 Layer:  BOARD GEOMETRY/SILKSCREEN_TOP*
G04 *
G04 Offset:    (0.00 0.00)*
G04 Mirror:    No*
G04 Mode:      Positive*
G04 Rotation:  0*
G04 FullContactRelief:  No*
G04 UndefLineWidth:     6.00*
G04 ================== end FILE IDENTIFICATION RECORD ====================*
%FSLAX25Y25*MOIN*%
%IR0*IPPOS*OFA0.00000B0.00000*MIA0B0*SFA1.00000B1.00000*%
%ADD10C,.01*%
%ADD11C,.006*%
G75*
%LPD*%
G75*
G36*
G01X28579Y506115D02*
X30093Y503085D01*
X27064D01*
X28579Y506115D01*
G37*
G36*
G01X25200Y722559D02*
X22200Y721059D01*
Y724059D01*
X25200Y722559D01*
G37*
G36*
G01X29859Y752800D02*
X28359Y755800D01*
X31359D01*
X29859Y752800D01*
G37*
G36*
G01X45000Y643441D02*
X48000Y641941D01*
Y644941D01*
X45000Y643441D01*
G37*
G36*
G01Y654441D02*
X48000Y652941D01*
Y655941D01*
X45000Y654441D01*
G37*
G36*
G01Y666941D02*
X48000Y665441D01*
Y668441D01*
X45000Y666941D01*
G37*
G36*
G01Y679441D02*
X48000Y677941D01*
Y680941D01*
X45000Y679441D01*
G37*
G36*
G01X83052Y93579D02*
X84466Y92165D01*
X85881Y94994D01*
X83052Y93579D01*
G37*
G36*
G01X80753Y452010D02*
X82167Y450596D01*
X83582Y453425D01*
X80753Y452010D01*
G37*
G36*
G01X89224Y522300D02*
X85224D01*
X87224Y518300D01*
X89224Y522300D01*
G37*
G36*
G01X83441Y583200D02*
X84941Y580200D01*
X81941D01*
X83441Y583200D01*
G37*
G36*
G01X80302Y819053D02*
Y817053D01*
X83302Y818053D01*
X80302Y819053D01*
G37*
G36*
G01X83239Y1177056D02*
X84971Y1176056D01*
X85605Y1179154D01*
X83239Y1177056D01*
G37*
G36*
G01X121735Y82585D02*
X120321Y83999D01*
X118906Y81170D01*
X121735Y82585D01*
G37*
G36*
G01X119053Y420698D02*
X117053D01*
X118053Y417698D01*
X119053Y420698D01*
G37*
G36*
G01X116556Y493950D02*
X120556D01*
X118556Y497950D01*
X116556Y493950D01*
G37*
G36*
G01X118553Y785698D02*
X116553D01*
X117553Y782698D01*
X118553Y785698D01*
G37*
G36*
G01X103555Y1026853D02*
X103055Y1027403D01*
X107190Y1031701D01*
X106701Y1037131D01*
X102855Y1041103D01*
X103105Y1041803D01*
X103805Y1041903D01*
X106526Y1039075D01*
X106418Y1040271D01*
X107658Y1041271D01*
X108658Y1041321D01*
X109608Y1041771D01*
X111758D01*
X112308Y1041521D01*
X113458Y1040671D01*
X113658D01*
X114058Y1041071D01*
X114858Y1040971D01*
X115208Y1040571D01*
Y1040035D01*
X117005Y1041903D01*
X117705Y1041803D01*
X117955Y1041103D01*
X115208Y1038266D01*
Y1037221D01*
X114958Y1036921D01*
X114358D01*
X113762Y1031554D01*
X113856Y1031456D01*
X113908Y1031421D01*
G02X114531Y1030754I-1089J-1641D01*
G01X117755Y1027403D01*
X117255Y1026853D01*
X116605Y1026903D01*
X114611Y1028962D01*
G02X111158Y1028721I-1792J818D01*
G01X107458D01*
X107331Y1030131D01*
X104205Y1026903D01*
X103555Y1026853D01*
G37*
G36*
G01X103833Y1026471D02*
X116983D01*
Y1024171D01*
X103833D01*
Y1026471D01*
G37*
G36*
G01X123698Y1142947D02*
Y1144947D01*
X120698Y1143947D01*
X123698Y1142947D01*
G37*
G36*
G01X125320Y721332D02*
Y723792D01*
X127500Y722500D01*
X125320Y721332D01*
G37*
G36*
G01X125820Y752332D02*
Y754792D01*
X128000Y753500D01*
X125820Y752332D01*
G37*
G36*
G01X161895Y522141D02*
X158865Y520627D01*
Y523656D01*
X161895Y522141D01*
G37*
G36*
G01X158300Y661441D02*
X161300Y662941D01*
Y659941D01*
X158300Y661441D01*
G37*
%LPC*%
G75*
G36*
G01X110405Y1035043D02*
X108039Y1037502D01*
X107958Y1038771D01*
X112858D01*
X112779Y1037511D01*
X110405Y1035043D01*
G37*
G36*
G01X109567Y1034172D02*
X108334Y1032890D01*
X108159Y1035625D01*
X109567Y1034172D01*
G37*
G36*
G01X112490Y1032876D02*
X111243Y1034172D01*
X112662Y1035637D01*
X112490Y1032876D01*
G37*
G36*
G01X112158Y1031471D02*
G03X110858Y1030121I849J-2119D01*
G01X108508Y1030171D01*
X108437Y1031274D01*
X110405Y1033306D01*
X112175Y1031478D01*
X112158Y1031471D01*
G37*
%LPD*%
G75*
G36*
G01X109058Y1037721D02*
X111758D01*
Y1036971D01*
X109058D01*
Y1037721D01*
G37*
G54D10*
G01X88042Y1025122D02*
X89142Y1025722D01*
Y1020722D01*
G01X81542Y1023422D02*
X86742D01*
X86642Y1024122D01*
X86542Y1024422D01*
X86342Y1024822D01*
X86042Y1025222D01*
X85542Y1025622D01*
X85142Y1025822D01*
X84842Y1025922D01*
X84342Y1026022D01*
X83942D01*
X83442Y1025922D01*
X83142Y1025822D01*
X82742Y1025622D01*
X82342Y1025322D01*
X82242Y1025222D01*
X81942Y1024822D01*
X81742Y1024422D01*
X81642Y1024122D01*
X81542Y1023522D01*
Y1023222D01*
X81642Y1022722D01*
X81742Y1022422D01*
X81942Y1022022D01*
X82242Y1021622D01*
X82742Y1021222D01*
X83142Y1021022D01*
X83442Y1020922D01*
X84042Y1020822D01*
X84142D01*
X84842Y1020922D01*
X85142Y1021022D01*
X85342Y1021122D01*
X85942Y1021522D01*
X86342Y1022022D01*
G01X80842Y1047222D02*
Y1037122D01*
G01Y1047222D02*
X83342D01*
G02Y1042222I0J-2500D01*
G01X80842D01*
G01X86942Y1047222D02*
Y1037122D01*
G01X91752Y1039522D02*
G03I-2410J0D01*
G54D11*
G01X-320500Y-470483D02*
Y2626000D01*
X2967000D01*
Y-470483D01*
X-320500D01*
G01X138740Y5906D02*
X144646Y0D01*
X187795D01*
G03X203543Y15748I0J15748D01*
G01Y1311024D01*
G03X187795Y1326772I-15748J0D01*
G01X15748D01*
G03X0Y1311024I0J-15748D01*
G01Y15748D01*
G03X15748Y0I15748J0D01*
G01X58898D01*
X64803Y5906D01*
Y43307D01*
G02X74252I4724J0D01*
G01Y7283D01*
X80157Y1378D01*
X99488D01*
X105394Y7283D01*
Y43307D01*
G02X108150I1378J0D01*
G01Y7283D01*
X114055Y1378D01*
X123386D01*
X129291Y7283D01*
Y43307D01*
G02X138740I4724J0D01*
G01Y5906D01*
G01X27362Y41378D02*
G02X33268I2953J0D01*
G02X27362I-2953J0D01*
G01Y404764D02*
G02X33268I2953J0D01*
G02X27362I-2953J0D01*
G01Y768150D02*
G02X33268I2953J0D01*
G02X27362I-2953J0D01*
G01Y1131535D02*
G02X33268I2953J0D01*
G02X27362I-2953J0D01*
G01X32908Y574289D02*
X36832Y621205D01*
G02X48601I5885J-492D01*
G01X52525Y574289D01*
G02X32908I-9808J-820D01*
G01X54467Y1240066D02*
X57760Y1243225D01*
G01X54332Y1240165D02*
X57645Y1243343D01*
G01X54206Y1240271D02*
X57531Y1243460D01*
G01X54087Y1240385D02*
X57428Y1243589D01*
G01X53968Y1240497D02*
X57335Y1243727D01*
G01X53849Y1240610D02*
X57243Y1243866D01*
G01X53730Y1240723D02*
X57150Y1244004D01*
G01X53611Y1240836D02*
X57057Y1244142D01*
G01X53491Y1240949D02*
X56965Y1244281D01*
G01X53384Y1241074D02*
X56872Y1244419D01*
G01X53283Y1241203D02*
X56798Y1244576D01*
G01X53181Y1241333D02*
X56728Y1244735D01*
G01X54467Y1240066D02*
X57760Y1243225D01*
G01X54332Y1240165D02*
X57645Y1243343D01*
G01X54206Y1240271D02*
X57531Y1243460D01*
G01X54087Y1240385D02*
X57428Y1243589D01*
G01X53968Y1240497D02*
X57335Y1243727D01*
G01X53849Y1240610D02*
X57243Y1243866D01*
G01X53730Y1240723D02*
X57150Y1244004D01*
G01X53611Y1240836D02*
X57057Y1244142D01*
G01X53491Y1240949D02*
X56965Y1244281D01*
G01X53384Y1241074D02*
X56872Y1244419D01*
G01X53283Y1241203D02*
X56798Y1244576D01*
G01X53181Y1241333D02*
X56728Y1244735D01*
G01X53080Y1241463D02*
X56657Y1244894D01*
G01X52979Y1241593D02*
X56586Y1245054D01*
G01X52877Y1241723D02*
X56515Y1245213D01*
G01X52776Y1241853D02*
X56444Y1245372D01*
G01X52684Y1241992D02*
X56383Y1245540D01*
G01X52602Y1242140D02*
X56336Y1245722D01*
G01X52519Y1242288D02*
X56289Y1245906D01*
G01X52436Y1242436D02*
X56243Y1246088D01*
G01X52354Y1242584D02*
X56197Y1246270D01*
G01X52271Y1242732D02*
X56150Y1246453D01*
G01X52189Y1242880D02*
X56112Y1246644D01*
G01X52119Y1243041D02*
X56096Y1246856D01*
G01X52054Y1243205D02*
X56079Y1247067D01*
G01X51988Y1243369D02*
X56063Y1247278D01*
G01X51922Y1243533D02*
X56047Y1247490D01*
G01X51856Y1243697D02*
X56030Y1247701D01*
G01X51791Y1243862D02*
X56049Y1247946D01*
G01X51734Y1244034D02*
X56075Y1248198D01*
G01X51683Y1244213D02*
X56102Y1248451D01*
G01X51632Y1244391D02*
X56128Y1248704D01*
G01X51582Y1244570D02*
X56155Y1248957D01*
G01X51531Y1244749D02*
X56242Y1249268D01*
G01X51481Y1244928D02*
X56338Y1249587D01*
G01X51443Y1245119D02*
X56435Y1249907D01*
G01X51406Y1245311D02*
X56580Y1250274D01*
G01X51369Y1245502D02*
X56816Y1250727D01*
G01X51332Y1245694D02*
X57129Y1251254D01*
G01X63144Y1257253D02*
X51296Y1245887D01*
G01X62935Y1257278D02*
X51271Y1246090D01*
G01X62725Y1257304D02*
X51247Y1246293D01*
G01X53080Y1241463D02*
X56657Y1244894D01*
G01X52979Y1241593D02*
X56586Y1245054D01*
G01X52877Y1241723D02*
X56515Y1245213D01*
G01X52776Y1241853D02*
X56444Y1245372D01*
G01X52684Y1241992D02*
X56383Y1245540D01*
G01X52602Y1242140D02*
X56336Y1245722D01*
G01X52519Y1242288D02*
X56289Y1245906D01*
G01X52436Y1242436D02*
X56243Y1246088D01*
G01X52354Y1242584D02*
X56197Y1246270D01*
G01X52271Y1242732D02*
X56150Y1246453D01*
G01X52189Y1242880D02*
X56112Y1246644D01*
G01X52119Y1243041D02*
X56096Y1246856D01*
G01X52054Y1243205D02*
X56079Y1247067D01*
G01X51988Y1243369D02*
X56063Y1247278D01*
G01X51922Y1243533D02*
X56047Y1247490D01*
G01X51856Y1243697D02*
X56030Y1247701D01*
G01X51791Y1243862D02*
X56049Y1247946D01*
G01X51734Y1244034D02*
X56075Y1248198D01*
G01X51683Y1244213D02*
X56102Y1248451D01*
G01X51632Y1244391D02*
X56128Y1248704D01*
G01X51582Y1244570D02*
X56155Y1248957D01*
G01X51531Y1244749D02*
X56242Y1249268D01*
G01X51481Y1244928D02*
X56338Y1249587D01*
G01X51443Y1245119D02*
X56435Y1249907D01*
G01X51406Y1245311D02*
X56580Y1250274D01*
G01X51369Y1245502D02*
X56816Y1250727D01*
G01X51332Y1245694D02*
X57129Y1251254D01*
G01X63144Y1257253D02*
X51296Y1245887D01*
G01X62935Y1257278D02*
X51271Y1246090D01*
G01X62725Y1257304D02*
X51247Y1246293D01*
G01X62515Y1257331D02*
X51222Y1246497D01*
G01X62295Y1257347D02*
X51196Y1246700D01*
G01X62067Y1257356D02*
X51183Y1246914D01*
G01X61840Y1257365D02*
X51169Y1247128D01*
G01X61612Y1257373D02*
X51155Y1247341D01*
G01X61385Y1257382D02*
X51148Y1247563D01*
G01X61139Y1257373D02*
X51144Y1247785D01*
G01X60891Y1257363D02*
X51149Y1248017D01*
G01X60642Y1257351D02*
X51160Y1248255D01*
G01X60393Y1257340D02*
X51171Y1248493D01*
G01X60145Y1257329D02*
X51182Y1248731D01*
G01X59868Y1257290D02*
X51216Y1248990D01*
G01X59590Y1257251D02*
X51253Y1249253D01*
G01X59312Y1257212D02*
X51290Y1249516D01*
G01X59035Y1257173D02*
X51344Y1249795D01*
G01X58723Y1257101D02*
X51414Y1250089D01*
G01X58407Y1257024D02*
X51484Y1250383D01*
G01X58089Y1256947D02*
X51580Y1250703D01*
G01X57743Y1256843D02*
X51694Y1251039D01*
G01X57370Y1256711D02*
X51812Y1251380D01*
G01X56995Y1256579D02*
X51991Y1251778D01*
G01X56540Y1256370D02*
X52172Y1252179D01*
G01X56072Y1256149D02*
X52455Y1252678D01*
G01X55444Y1255773D02*
X52835Y1253270D01*
G01X62515Y1257331D02*
X51222Y1246497D01*
G01X62295Y1257347D02*
X51196Y1246700D01*
G01X62067Y1257356D02*
X51183Y1246914D01*
G01X61840Y1257365D02*
X51169Y1247128D01*
G01X61612Y1257373D02*
X51155Y1247341D01*
G01X61385Y1257382D02*
X51148Y1247563D01*
G01X61139Y1257373D02*
X51144Y1247785D01*
G01X60891Y1257363D02*
X51149Y1248017D01*
G01X60642Y1257351D02*
X51160Y1248255D01*
G01X60393Y1257340D02*
X51171Y1248493D01*
G01X60145Y1257329D02*
X51182Y1248731D01*
G01X59868Y1257290D02*
X51216Y1248990D01*
G01X59590Y1257251D02*
X51253Y1249253D01*
G01X59312Y1257212D02*
X51290Y1249516D01*
G01X59035Y1257173D02*
X51344Y1249795D01*
G01X58723Y1257101D02*
X51414Y1250089D01*
G01X58407Y1257024D02*
X51484Y1250383D01*
G01X58089Y1256947D02*
X51580Y1250703D01*
G01X57743Y1256843D02*
X51694Y1251039D01*
G01X57370Y1256711D02*
X51812Y1251380D01*
G01X56995Y1256579D02*
X51991Y1251778D01*
G01X56540Y1256370D02*
X52172Y1252179D01*
G01X56072Y1256149D02*
X52455Y1252678D01*
G01X55444Y1255773D02*
X52835Y1253270D01*
G01X58475Y1238232D02*
X62116Y1241725D01*
G01X58291Y1238282D02*
X61849Y1241695D01*
G01X58108Y1238334D02*
X61581Y1241666D01*
G01X57923Y1238384D02*
X61313Y1241636D01*
G01X57739Y1238434D02*
X61075Y1241635D01*
G01X57555Y1238486D02*
X60866Y1241661D01*
G01X57371Y1238536D02*
X60656Y1241687D01*
G01X57196Y1238596D02*
X60446Y1241713D01*
G01X57029Y1238662D02*
X60236Y1241739D01*
G01X56861Y1238728D02*
X60042Y1241780D01*
G01X56694Y1238795D02*
X59874Y1241845D01*
G01X56526Y1238861D02*
X59705Y1241911D01*
G01X56359Y1238928D02*
X59537Y1241976D01*
G01X56191Y1238994D02*
X59368Y1242042D01*
G01X56040Y1239076D02*
X59199Y1242107D01*
G01X55889Y1239159D02*
X59046Y1242188D01*
G01X55738Y1239241D02*
X58907Y1242282D01*
G01X55587Y1239324D02*
X58769Y1242376D01*
G01X55436Y1239407D02*
X58630Y1242470D01*
G01X55285Y1239489D02*
X58491Y1242564D01*
G01X55140Y1239577D02*
X58352Y1242658D01*
G01X55005Y1239675D02*
X58218Y1242756D01*
G01X54871Y1239773D02*
X58103Y1242873D01*
G01X54736Y1239870D02*
X57988Y1242991D01*
G01X54601Y1239969D02*
X57874Y1243108D01*
G01X58475Y1238232D02*
X62116Y1241725D01*
G01X58291Y1238282D02*
X61849Y1241695D01*
G01X58108Y1238334D02*
X61581Y1241666D01*
G01X57923Y1238384D02*
X61313Y1241636D01*
G01X57739Y1238434D02*
X61075Y1241635D01*
G01X57555Y1238486D02*
X60866Y1241661D01*
G01X57371Y1238536D02*
X60656Y1241687D01*
G01X57196Y1238596D02*
X60446Y1241713D01*
G01X57029Y1238662D02*
X60236Y1241739D01*
G01X56861Y1238728D02*
X60042Y1241780D01*
G01X56694Y1238795D02*
X59874Y1241845D01*
G01X56526Y1238861D02*
X59705Y1241911D01*
G01X56359Y1238928D02*
X59537Y1241976D01*
G01X56191Y1238994D02*
X59368Y1242042D01*
G01X56040Y1239076D02*
X59199Y1242107D01*
G01X55889Y1239159D02*
X59046Y1242188D01*
G01X55738Y1239241D02*
X58907Y1242282D01*
G01X55587Y1239324D02*
X58769Y1242376D01*
G01X55436Y1239407D02*
X58630Y1242470D01*
G01X55285Y1239489D02*
X58491Y1242564D01*
G01X55140Y1239577D02*
X58352Y1242658D01*
G01X55005Y1239675D02*
X58218Y1242756D01*
G01X54871Y1239773D02*
X58103Y1242873D01*
G01X54736Y1239870D02*
X57988Y1242991D01*
G01X54601Y1239969D02*
X57874Y1243108D01*
G01X77476Y1238368D02*
X87908Y1248375D01*
G01X77260Y1238388D02*
X87956Y1248648D01*
G01X77044Y1238407D02*
X88004Y1248921D01*
G01X88052Y1249195D02*
X76828Y1238429D01*
G01X76612Y1238448D02*
X81294Y1242940D01*
G01X76396Y1238467D02*
X80833Y1242724D01*
G01X76197Y1238503D02*
X80509Y1242641D01*
G01X76020Y1238562D02*
X80197Y1242568D01*
G01X75844Y1238620D02*
X79942Y1242551D01*
G01X75668Y1238678D02*
X79688Y1242534D01*
G01X75491Y1238735D02*
X79449Y1242532D01*
G01X75314Y1238794D02*
X79227Y1242547D01*
G01X75138Y1238852D02*
X79006Y1242563D01*
G01X74981Y1238929D02*
X78805Y1242596D01*
G01X74842Y1239023D02*
X78619Y1242645D01*
G01X74703Y1239116D02*
X78433Y1242694D01*
G01X74565Y1239211D02*
X78270Y1242765D01*
G01X74426Y1239305D02*
X78122Y1242850D01*
G01X74287Y1239398D02*
X77973Y1242935D01*
G01X71796Y1236242D02*
X71804Y1236249D01*
G01X74149Y1239493D02*
X77849Y1243043D01*
G01X71473Y1236158D02*
X71668Y1236345D01*
G01X71150Y1236077D02*
X71531Y1236442D01*
G01X74031Y1239607D02*
X77740Y1243166D01*
G01X73928Y1239736D02*
X77632Y1243288D01*
G01X70828Y1235994D02*
X71394Y1236538D01*
G01X73825Y1239864D02*
X77541Y1243428D01*
G01X70505Y1235911D02*
X71258Y1236634D01*
G01X70182Y1235830D02*
X71121Y1236731D01*
G01X73722Y1239993D02*
X77471Y1243589D01*
G01X73619Y1240121D02*
X77401Y1243749D01*
G01X69859Y1235746D02*
X70985Y1236827D01*
G01X69537Y1235664D02*
X70849Y1236923D01*
G01X73517Y1240250D02*
X77338Y1243915D01*
G01X73413Y1240378D02*
X77305Y1244112D01*
G01X69213Y1235582D02*
X70713Y1237019D01*
G01X68939Y1235545D02*
X70576Y1237116D01*
G01X73334Y1240530D02*
X77272Y1244308D01*
G01X68772Y1235613D02*
X70440Y1237213D01*
G01X73266Y1240691D02*
X77240Y1244503D01*
G01X73197Y1240852D02*
X77232Y1244723D01*
G01X68604Y1235678D02*
X70304Y1237308D01*
G01X73129Y1241014D02*
X77234Y1244952D01*
G01X68436Y1235746D02*
X70168Y1237406D01*
G01X68269Y1235811D02*
X70031Y1237502D01*
G01X73060Y1241175D02*
X77236Y1245181D01*
G01X72992Y1241337D02*
X77238Y1245410D01*
G01X68101Y1235877D02*
X69895Y1237599D01*
G01X67933Y1235944D02*
X69759Y1237695D01*
G01X67765Y1236009D02*
X69622Y1237791D01*
G01X67597Y1236077D02*
X69486Y1237889D01*
G01X67429Y1236142D02*
X69350Y1237984D01*
G01X67261Y1236207D02*
X69214Y1238081D01*
G01X67092Y1236273D02*
X69078Y1238178D01*
G01X66924Y1236339D02*
X68941Y1238274D01*
G01X66755Y1236405D02*
X68805Y1238372D01*
G01X66587Y1236470D02*
X68669Y1238467D01*
G01X66418Y1236535D02*
X68533Y1238564D01*
G01X66249Y1236600D02*
X68397Y1238661D01*
G01X66080Y1236665D02*
X68261Y1238757D01*
G01X65911Y1236731D02*
X68125Y1238854D01*
G01X65742Y1236796D02*
X67989Y1238951D01*
G01X65572Y1236861D02*
X67852Y1239047D01*
G01X65403Y1236925D02*
X67716Y1239144D01*
G01X65232Y1236988D02*
X67580Y1239240D01*
G01X67444Y1239337D02*
X65062Y1237053D01*
G01X64892Y1237117D02*
X67308Y1239434D01*
G01X64722Y1237181D02*
X69795Y1242047D01*
G01X64551Y1237243D02*
X70085Y1242553D01*
G01X64380Y1237307D02*
X70334Y1243019D01*
G01X64208Y1237369D02*
X70481Y1243387D01*
G01X64036Y1237432D02*
X70627Y1243754D01*
G01X63864Y1237493D02*
X70755Y1244104D01*
G01X63690Y1237554D02*
X70832Y1244405D01*
G01X63516Y1237615D02*
X70909Y1244707D01*
G01X63340Y1237672D02*
X70986Y1245007D01*
G01X63163Y1237729D02*
X71055Y1245301D01*
G01X62980Y1237783D02*
X71091Y1245563D01*
G01X62780Y1237817D02*
X71128Y1245825D01*
G01X62550Y1237824D02*
X71164Y1246087D01*
G01X62320Y1237829D02*
X71200Y1246348D01*
G01X62090Y1237837D02*
X71236Y1246610D01*
G01X61860Y1237843D02*
X71245Y1246847D01*
G01X61629Y1237850D02*
X71255Y1247083D01*
G01X61399Y1237856D02*
X71265Y1247319D01*
G01X61174Y1237867D02*
X71275Y1247557D01*
G01X60959Y1237888D02*
X71285Y1247794D01*
G01X60743Y1237908D02*
X71295Y1248030D01*
G01X60527Y1237928D02*
X71291Y1248253D01*
G01X60312Y1237949D02*
X71282Y1248473D01*
G01X60096Y1237969D02*
X71267Y1248685D01*
G01X59880Y1237989D02*
X71246Y1248893D01*
G01X59676Y1238019D02*
X71226Y1249100D01*
G01X71200Y1249302D02*
X59475Y1238054D01*
G01X59275Y1238090D02*
X63729Y1242363D01*
G01X59075Y1238125D02*
X63162Y1242046D01*
G01X58875Y1238160D02*
X62792Y1241919D01*
G01X58674Y1238195D02*
X62421Y1241790D01*
G01X70182Y1235830D02*
X70505Y1235911D01*
G01X71796Y1236242D02*
X71473Y1236158D01*
G01X69859Y1235746D02*
X70182Y1235830D01*
G01X69537Y1235664D02*
X69859Y1235746D01*
G01X71150Y1236077D02*
X71473Y1236158D01*
G01X70505Y1235911D02*
X70828Y1235994D01*
G01D02*
X71150Y1236077D01*
G01X69213Y1235582D02*
X69537Y1235664D01*
G01X77476Y1238368D02*
X87908Y1248375D01*
G01X77260Y1238388D02*
X87956Y1248648D01*
G01X77044Y1238407D02*
X88004Y1248921D01*
G01X88052Y1249195D02*
X76828Y1238429D01*
G01X76612Y1238448D02*
X81294Y1242940D01*
G01X76396Y1238467D02*
X80833Y1242724D01*
G01X76197Y1238503D02*
X80509Y1242641D01*
G01X76020Y1238562D02*
X80197Y1242568D01*
G01X75844Y1238620D02*
X79942Y1242551D01*
G01X75668Y1238678D02*
X79688Y1242534D01*
G01X75491Y1238735D02*
X79449Y1242532D01*
G01X75314Y1238794D02*
X79227Y1242547D01*
G01X75138Y1238852D02*
X79006Y1242563D01*
G01X74981Y1238929D02*
X78805Y1242596D01*
G01X74842Y1239023D02*
X78619Y1242645D01*
G01X74703Y1239116D02*
X78433Y1242694D01*
G01X74565Y1239211D02*
X78270Y1242765D01*
G01X74426Y1239305D02*
X78122Y1242850D01*
G01X74287Y1239398D02*
X77973Y1242935D01*
G01X71796Y1236242D02*
X71804Y1236249D01*
G01X74149Y1239493D02*
X77849Y1243043D01*
G01X71473Y1236158D02*
X71668Y1236345D01*
G01X71150Y1236077D02*
X71531Y1236442D01*
G01X74031Y1239607D02*
X77740Y1243166D01*
G01X73928Y1239736D02*
X77632Y1243288D01*
G01X70828Y1235994D02*
X71394Y1236538D01*
G01X73825Y1239864D02*
X77541Y1243428D01*
G01X70505Y1235911D02*
X71258Y1236634D01*
G01X70182Y1235830D02*
X71121Y1236731D01*
G01X73722Y1239993D02*
X77471Y1243589D01*
G01X73619Y1240121D02*
X77401Y1243749D01*
G01X69859Y1235746D02*
X70985Y1236827D01*
G01X69537Y1235664D02*
X70849Y1236923D01*
G01X73517Y1240250D02*
X77338Y1243915D01*
G01X73413Y1240378D02*
X77305Y1244112D01*
G01X69213Y1235582D02*
X70713Y1237019D01*
G01X68939Y1235545D02*
X70576Y1237116D01*
G01X73334Y1240530D02*
X77272Y1244308D01*
G01X68772Y1235613D02*
X70440Y1237213D01*
G01X73266Y1240691D02*
X77240Y1244503D01*
G01X73197Y1240852D02*
X77232Y1244723D01*
G01X68604Y1235678D02*
X70304Y1237308D01*
G01X73129Y1241014D02*
X77234Y1244952D01*
G01X68436Y1235746D02*
X70168Y1237406D01*
G01X68269Y1235811D02*
X70031Y1237502D01*
G01X73060Y1241175D02*
X77236Y1245181D01*
G01X72992Y1241337D02*
X77238Y1245410D01*
G01X68101Y1235877D02*
X69895Y1237599D01*
G01X67933Y1235944D02*
X69759Y1237695D01*
G01X67765Y1236009D02*
X69622Y1237791D01*
G01X67597Y1236077D02*
X69486Y1237889D01*
G01X67429Y1236142D02*
X69350Y1237984D01*
G01X67261Y1236207D02*
X69214Y1238081D01*
G01X67092Y1236273D02*
X69078Y1238178D01*
G01X66924Y1236339D02*
X68941Y1238274D01*
G01X66755Y1236405D02*
X68805Y1238372D01*
G01X66587Y1236470D02*
X68669Y1238467D01*
G01X66418Y1236535D02*
X68533Y1238564D01*
G01X66249Y1236600D02*
X68397Y1238661D01*
G01X66080Y1236665D02*
X68261Y1238757D01*
G01X65911Y1236731D02*
X68125Y1238854D01*
G01X65742Y1236796D02*
X67989Y1238951D01*
G01X65572Y1236861D02*
X67852Y1239047D01*
G01X65403Y1236925D02*
X67716Y1239144D01*
G01X65232Y1236988D02*
X67580Y1239240D01*
G01X67444Y1239337D02*
X65062Y1237053D01*
G01X64892Y1237117D02*
X67308Y1239434D01*
G01X64722Y1237181D02*
X69795Y1242047D01*
G01X64551Y1237243D02*
X70085Y1242553D01*
G01X64380Y1237307D02*
X70334Y1243019D01*
G01X64208Y1237369D02*
X70481Y1243387D01*
G01X64036Y1237432D02*
X70627Y1243754D01*
G01X63864Y1237493D02*
X70755Y1244104D01*
G01X63690Y1237554D02*
X70832Y1244405D01*
G01X63516Y1237615D02*
X70909Y1244707D01*
G01X63340Y1237672D02*
X70986Y1245007D01*
G01X63163Y1237729D02*
X71055Y1245301D01*
G01X62980Y1237783D02*
X71091Y1245563D01*
G01X62780Y1237817D02*
X71128Y1245825D01*
G01X62550Y1237824D02*
X71164Y1246087D01*
G01X62320Y1237829D02*
X71200Y1246348D01*
G01X62090Y1237837D02*
X71236Y1246610D01*
G01X61860Y1237843D02*
X71245Y1246847D01*
G01X61629Y1237850D02*
X71255Y1247083D01*
G01X61399Y1237856D02*
X71265Y1247319D01*
G01X61174Y1237867D02*
X71275Y1247557D01*
G01X60959Y1237888D02*
X71285Y1247794D01*
G01X60743Y1237908D02*
X71295Y1248030D01*
G01X60527Y1237928D02*
X71291Y1248253D01*
G01X60312Y1237949D02*
X71282Y1248473D01*
G01X60096Y1237969D02*
X71267Y1248685D01*
G01X59880Y1237989D02*
X71246Y1248893D01*
G01X59676Y1238019D02*
X71226Y1249100D01*
G01X71200Y1249302D02*
X59475Y1238054D01*
G01X59275Y1238090D02*
X63729Y1242363D01*
G01X59075Y1238125D02*
X63162Y1242046D01*
G01X58875Y1238160D02*
X62792Y1241919D01*
G01X58674Y1238195D02*
X62421Y1241790D01*
G01X70182Y1235830D02*
X70505Y1235911D01*
G01X71796Y1236242D02*
X71473Y1236158D01*
G01X69859Y1235746D02*
X70182Y1235830D01*
G01X69537Y1235664D02*
X69859Y1235746D01*
G01X71150Y1236077D02*
X71473Y1236158D01*
G01X70505Y1235911D02*
X70828Y1235994D01*
G01D02*
X71150Y1236077D01*
G01X69213Y1235582D02*
X69537Y1235664D01*
G01X72923Y1241498D02*
X77272Y1245670D01*
G01X72882Y1241686D02*
X77305Y1245929D01*
G01X72847Y1241880D02*
X77339Y1246189D01*
G01X72813Y1242074D02*
X77373Y1246449D01*
G01X72777Y1242267D02*
X77421Y1246721D01*
G01X72743Y1242461D02*
X77469Y1246995D01*
G01X72708Y1242655D02*
X77516Y1247268D01*
G01X72674Y1242849D02*
X77565Y1247541D01*
G01X72672Y1243075D02*
X77613Y1247815D01*
G01X72670Y1243301D02*
X77661Y1248088D01*
G01X72668Y1243526D02*
X77708Y1248361D01*
G01X72667Y1243752D02*
X77756Y1248634D01*
G01X72665Y1243977D02*
X77805Y1248907D01*
G01X72663Y1244203D02*
X77852Y1249180D01*
G01X77900Y1249454D02*
X72671Y1244438D01*
G01X77948Y1249727D02*
X72703Y1244695D01*
G01X77997Y1250000D02*
X72734Y1244952D01*
G01X78044Y1250274D02*
X72765Y1245209D01*
G01X78092Y1250547D02*
X72796Y1245467D01*
G01X78140Y1250820D02*
X72828Y1245724D01*
G01X78188Y1251093D02*
X72859Y1245981D01*
G01X78236Y1251366D02*
X72902Y1246249D01*
G01X71167Y1249498D02*
X65228Y1243800D01*
G01X71135Y1249694D02*
X65589Y1244375D01*
G01X71101Y1249890D02*
X65769Y1244774D01*
G01X71064Y1250081D02*
X65949Y1245174D01*
G01X71018Y1250264D02*
X66037Y1245486D01*
G01X70973Y1250447D02*
X66113Y1245785D01*
G01X70926Y1250630D02*
X66189Y1246085D01*
G01X72950Y1246523D02*
X72902Y1246249D01*
G01X72923Y1241498D02*
X77272Y1245670D01*
G01X72882Y1241686D02*
X77305Y1245929D01*
G01X72847Y1241880D02*
X77339Y1246189D01*
G01X72813Y1242074D02*
X77373Y1246449D01*
G01X72777Y1242267D02*
X77421Y1246721D01*
G01X72743Y1242461D02*
X77469Y1246995D01*
G01X72708Y1242655D02*
X77516Y1247268D01*
G01X72674Y1242849D02*
X77565Y1247541D01*
G01X72672Y1243075D02*
X77613Y1247815D01*
G01X72670Y1243301D02*
X77661Y1248088D01*
G01X72668Y1243526D02*
X77708Y1248361D01*
G01X72667Y1243752D02*
X77756Y1248634D01*
G01X72665Y1243977D02*
X77805Y1248907D01*
G01X72663Y1244203D02*
X77852Y1249180D01*
G01X77900Y1249454D02*
X72671Y1244438D01*
G01X77948Y1249727D02*
X72703Y1244695D01*
G01X77997Y1250000D02*
X72734Y1244952D01*
G01X78044Y1250274D02*
X72765Y1245209D01*
G01X78092Y1250547D02*
X72796Y1245467D01*
G01X78140Y1250820D02*
X72828Y1245724D01*
G01X78188Y1251093D02*
X72859Y1245981D01*
G01X78236Y1251366D02*
X72902Y1246249D01*
G01X71167Y1249498D02*
X65228Y1243800D01*
G01X71135Y1249694D02*
X65589Y1244375D01*
G01X71101Y1249890D02*
X65769Y1244774D01*
G01X71064Y1250081D02*
X65949Y1245174D01*
G01X71018Y1250264D02*
X66037Y1245486D01*
G01X70973Y1250447D02*
X66113Y1245785D01*
G01X70926Y1250630D02*
X66189Y1246085D01*
G01X72950Y1246523D02*
X72902Y1246249D01*
G01X78284Y1251639D02*
X72950Y1246523D01*
G01X78332Y1251913D02*
X72998Y1246796D01*
G01X78380Y1252186D02*
X73046Y1247069D01*
G01X78428Y1252459D02*
X73094Y1247343D01*
G01X78476Y1252733D02*
X73142Y1247616D01*
G01X78524Y1253005D02*
X73190Y1247889D01*
G01X78572Y1253279D02*
X73238Y1248162D01*
G01X78620Y1253552D02*
X73286Y1248435D01*
G01X78668Y1253826D02*
X73333Y1248708D01*
G01X78715Y1254098D02*
X73382Y1248982D01*
G01X78764Y1254371D02*
X73430Y1249255D01*
G01X78812Y1254645D02*
X73477Y1249528D01*
G01X78859Y1254918D02*
X73525Y1249802D01*
G01X78907Y1255192D02*
X73574Y1250074D01*
G01X78955Y1255464D02*
X73622Y1250348D01*
G01X78840Y1255581D02*
X73669Y1250621D01*
G01X78603Y1255581D02*
X73717Y1250895D01*
G01X78366Y1255581D02*
X73765Y1251167D01*
G01X78129Y1255581D02*
X73813Y1251440D01*
G01X77892Y1255581D02*
X73861Y1251714D01*
G01X77655Y1255581D02*
X73909Y1251987D01*
G01X77419Y1255581D02*
X73957Y1252261D01*
G01X77182Y1255581D02*
X74005Y1252533D01*
G01X76945Y1255581D02*
X74053Y1252807D01*
G01X76708Y1255581D02*
X74101Y1253080D01*
G01X76471Y1255581D02*
X74149Y1253353D01*
G01X76235Y1255581D02*
X74197Y1253626D01*
G01X75997Y1255581D02*
X74245Y1253900D01*
G01X75761Y1255581D02*
X74293Y1254173D01*
G01X75524Y1255581D02*
X74341Y1254446D01*
G01X75287Y1255581D02*
X74389Y1254719D01*
G01X75050Y1255581D02*
X74437Y1254992D01*
G01X70880Y1250813D02*
X66252Y1246373D01*
G01X74813Y1255581D02*
X74485Y1255266D01*
G01X70828Y1250990D02*
X66272Y1246620D01*
G01X74577Y1255581D02*
X74532Y1255539D01*
G01X70768Y1251160D02*
X66292Y1246866D01*
G01X70709Y1251330D02*
X66312Y1247113D01*
G01X70648Y1251500D02*
X66332Y1247359D01*
G01X70589Y1251670D02*
X66336Y1247590D01*
G01X70529Y1251839D02*
X66318Y1247800D01*
G01X70456Y1251997D02*
X66301Y1248011D01*
G01X70381Y1252152D02*
X66283Y1248221D01*
G01X70306Y1252307D02*
X66265Y1248432D01*
G01X70231Y1252463D02*
X66248Y1248642D01*
G01X70157Y1252618D02*
X66217Y1248839D01*
G01X70081Y1252773D02*
X66169Y1249021D01*
G01X69995Y1252918D02*
X66122Y1249203D01*
G01X69904Y1253058D02*
X66075Y1249385D01*
G01X69813Y1253197D02*
X66027Y1249566D01*
G01X69721Y1253337D02*
X65980Y1249747D01*
G01X69630Y1253477D02*
X65930Y1249927D01*
G01X69538Y1253616D02*
X65857Y1250084D01*
G01X69447Y1253755D02*
X65785Y1250242D01*
G01X69339Y1253879D02*
X65712Y1250400D01*
G01X69229Y1254001D02*
X65639Y1250557D01*
G01X69120Y1254123D02*
X65566Y1250714D01*
G01X69010Y1254245D02*
X65494Y1250872D01*
G01X68900Y1254367D02*
X65408Y1251017D01*
G01X68790Y1254488D02*
X65312Y1251152D01*
G01X68680Y1254610D02*
X65216Y1251287D01*
G01X68560Y1254722D02*
X65120Y1251422D01*
G01X68435Y1254830D02*
X65024Y1251557D01*
G01X68309Y1254937D02*
X64928Y1251692D01*
G01X68185Y1255044D02*
X64832Y1251828D01*
G01X68059Y1255150D02*
X64714Y1251942D01*
G01X67934Y1255257D02*
X64595Y1252054D01*
G01X67801Y1255358D02*
X64476Y1252168D01*
G01X67664Y1255453D02*
X64356Y1252280D01*
G01X67527Y1255548D02*
X64238Y1252394D01*
G01X67390Y1255644D02*
X64118Y1252506D01*
G01X67252Y1255740D02*
X63986Y1252606D01*
G01X67115Y1255835D02*
X63842Y1252696D01*
G01X66968Y1255921D02*
X63698Y1252784D01*
G01X66818Y1256005D02*
X63554Y1252874D01*
G01X66668Y1256088D02*
X63410Y1252963D01*
G01X66518Y1256172D02*
X63265Y1253051D01*
G01X66368Y1256255D02*
X63109Y1253129D01*
G01X66217Y1256336D02*
X62936Y1253190D01*
G01X66052Y1256407D02*
X62762Y1253250D01*
G01X65889Y1256477D02*
X62588Y1253311D01*
G01X65726Y1256547D02*
X62415Y1253371D01*
G01X65562Y1256618D02*
X62242Y1253433D01*
G01X65399Y1256688D02*
X62037Y1253464D01*
G01X65225Y1256749D02*
X61825Y1253487D01*
G01X65047Y1256806D02*
X61613Y1253511D01*
G01X64869Y1256862D02*
X61402Y1253536D01*
G01X64691Y1256918D02*
X61189Y1253559D01*
G01X64513Y1256975D02*
X60927Y1253535D01*
G01X64328Y1257025D02*
X60658Y1253504D01*
G01X64135Y1257067D02*
X60388Y1253473D01*
G01X63941Y1257108D02*
X60078Y1253402D01*
G01X63748Y1257150D02*
X59709Y1253276D01*
G01X63555Y1257192D02*
X59341Y1253149D01*
G01X63355Y1257227D02*
X58747Y1252807D01*
G01X77565Y1247541D02*
X77613Y1247815D01*
G01X77421Y1246721D02*
X77469Y1246995D01*
G01X77613Y1247815D02*
X77661Y1248088D01*
G01X77373Y1246449D02*
X77421Y1246721D01*
G01X77516Y1247268D02*
X77565Y1247541D01*
G01X77661Y1248088D02*
X77708Y1248361D01*
G01X77892Y1255581D02*
X77655D01*
G01D02*
X77419D01*
G01X76945D02*
X76708D01*
G01X77419D02*
X77182D01*
G01D02*
X76945D01*
G01X75050D02*
X74813D01*
G01X76708D02*
X76471D01*
G01X74813D02*
X74577D01*
G01X75287D02*
X75050D01*
G01X76471D02*
X76235D01*
G01D02*
X75997D01*
G01D02*
X75761D01*
G01X75524D02*
X75287D01*
G01X75761D02*
X75524D01*
G01X77469Y1246995D02*
X77516Y1247268D01*
G01X74293Y1254173D02*
X74341Y1254446D01*
G01X74389Y1254719D02*
X74437Y1254992D01*
G01X74341Y1254446D02*
X74389Y1254719D01*
G01X74245Y1253900D02*
X74293Y1254173D01*
G01X74437Y1254992D02*
X74485Y1255266D01*
G01X74101Y1253080D02*
X74053Y1252807D01*
G01X74197Y1253626D02*
X74245Y1253900D01*
G01X74149Y1253353D02*
X74197Y1253626D01*
G01X74101Y1253080D02*
X74149Y1253353D01*
G01X74577Y1255581D02*
X74540D01*
X74532Y1255539D01*
G01X74053Y1252807D02*
X74005Y1252533D01*
G01X74485Y1255266D02*
X74532Y1255539D01*
G01X73190Y1247889D02*
X73142Y1247616D01*
G01X73333Y1248708D02*
X73286Y1248435D01*
G01D02*
X73238Y1248162D01*
G01X73477Y1249528D02*
X73430Y1249255D01*
G01D02*
X73382Y1248982D01*
G01D02*
X73333Y1248708D01*
G01X73238Y1248162D02*
X73190Y1247889D01*
G01X74005Y1252533D02*
X73957Y1252261D01*
G01X73142Y1247616D02*
X73094Y1247343D01*
G01D02*
X73046Y1247069D01*
G01X73861Y1251714D02*
X73813Y1251440D01*
G01X73525Y1249802D02*
X73477Y1249528D01*
G01X73813Y1251440D02*
X73765Y1251167D01*
G01X73957Y1252261D02*
X73909Y1251987D01*
G01D02*
X73861Y1251714D01*
G01X73765Y1251167D02*
X73717Y1250895D01*
G01X73574Y1250074D02*
X73525Y1249802D01*
G01X73622Y1250348D02*
X73574Y1250074D01*
G01X73717Y1250895D02*
X73669Y1250621D01*
G01D02*
X73622Y1250348D01*
G01X73046Y1247069D02*
X72998Y1246796D01*
G01D02*
X72950Y1246523D01*
G01X78284Y1251639D02*
X72950Y1246523D01*
G01X78332Y1251913D02*
X72998Y1246796D01*
G01X78380Y1252186D02*
X73046Y1247069D01*
G01X78428Y1252459D02*
X73094Y1247343D01*
G01X78476Y1252733D02*
X73142Y1247616D01*
G01X78524Y1253005D02*
X73190Y1247889D01*
G01X78572Y1253279D02*
X73238Y1248162D01*
G01X78620Y1253552D02*
X73286Y1248435D01*
G01X78668Y1253826D02*
X73333Y1248708D01*
G01X78715Y1254098D02*
X73382Y1248982D01*
G01X78764Y1254371D02*
X73430Y1249255D01*
G01X78812Y1254645D02*
X73477Y1249528D01*
G01X78859Y1254918D02*
X73525Y1249802D01*
G01X78907Y1255192D02*
X73574Y1250074D01*
G01X78955Y1255464D02*
X73622Y1250348D01*
G01X78840Y1255581D02*
X73669Y1250621D01*
G01X78603Y1255581D02*
X73717Y1250895D01*
G01X78366Y1255581D02*
X73765Y1251167D01*
G01X78129Y1255581D02*
X73813Y1251440D01*
G01X77892Y1255581D02*
X73861Y1251714D01*
G01X77655Y1255581D02*
X73909Y1251987D01*
G01X77419Y1255581D02*
X73957Y1252261D01*
G01X77182Y1255581D02*
X74005Y1252533D01*
G01X76945Y1255581D02*
X74053Y1252807D01*
G01X76708Y1255581D02*
X74101Y1253080D01*
G01X76471Y1255581D02*
X74149Y1253353D01*
G01X76235Y1255581D02*
X74197Y1253626D01*
G01X75997Y1255581D02*
X74245Y1253900D01*
G01X75761Y1255581D02*
X74293Y1254173D01*
G01X75524Y1255581D02*
X74341Y1254446D01*
G01X75287Y1255581D02*
X74389Y1254719D01*
G01X75050Y1255581D02*
X74437Y1254992D01*
G01X70880Y1250813D02*
X66252Y1246373D01*
G01X74813Y1255581D02*
X74485Y1255266D01*
G01X70828Y1250990D02*
X66272Y1246620D01*
G01X74577Y1255581D02*
X74532Y1255539D01*
G01X70768Y1251160D02*
X66292Y1246866D01*
G01X70709Y1251330D02*
X66312Y1247113D01*
G01X70648Y1251500D02*
X66332Y1247359D01*
G01X70589Y1251670D02*
X66336Y1247590D01*
G01X70529Y1251839D02*
X66318Y1247800D01*
G01X70456Y1251997D02*
X66301Y1248011D01*
G01X70381Y1252152D02*
X66283Y1248221D01*
G01X70306Y1252307D02*
X66265Y1248432D01*
G01X70231Y1252463D02*
X66248Y1248642D01*
G01X70157Y1252618D02*
X66217Y1248839D01*
G01X70081Y1252773D02*
X66169Y1249021D01*
G01X69995Y1252918D02*
X66122Y1249203D01*
G01X69904Y1253058D02*
X66075Y1249385D01*
G01X69813Y1253197D02*
X66027Y1249566D01*
G01X69721Y1253337D02*
X65980Y1249747D01*
G01X69630Y1253477D02*
X65930Y1249927D01*
G01X69538Y1253616D02*
X65857Y1250084D01*
G01X69447Y1253755D02*
X65785Y1250242D01*
G01X69339Y1253879D02*
X65712Y1250400D01*
G01X69229Y1254001D02*
X65639Y1250557D01*
G01X69120Y1254123D02*
X65566Y1250714D01*
G01X69010Y1254245D02*
X65494Y1250872D01*
G01X68900Y1254367D02*
X65408Y1251017D01*
G01X68790Y1254488D02*
X65312Y1251152D01*
G01X68680Y1254610D02*
X65216Y1251287D01*
G01X68560Y1254722D02*
X65120Y1251422D01*
G01X68435Y1254830D02*
X65024Y1251557D01*
G01X68309Y1254937D02*
X64928Y1251692D01*
G01X68185Y1255044D02*
X64832Y1251828D01*
G01X68059Y1255150D02*
X64714Y1251942D01*
G01X67934Y1255257D02*
X64595Y1252054D01*
G01X67801Y1255358D02*
X64476Y1252168D01*
G01X67664Y1255453D02*
X64356Y1252280D01*
G01X67527Y1255548D02*
X64238Y1252394D01*
G01X67390Y1255644D02*
X64118Y1252506D01*
G01X67252Y1255740D02*
X63986Y1252606D01*
G01X67115Y1255835D02*
X63842Y1252696D01*
G01X66968Y1255921D02*
X63698Y1252784D01*
G01X66818Y1256005D02*
X63554Y1252874D01*
G01X66668Y1256088D02*
X63410Y1252963D01*
G01X66518Y1256172D02*
X63265Y1253051D01*
G01X66368Y1256255D02*
X63109Y1253129D01*
G01X66217Y1256336D02*
X62936Y1253190D01*
G01X66052Y1256407D02*
X62762Y1253250D01*
G01X65889Y1256477D02*
X62588Y1253311D01*
G01X65726Y1256547D02*
X62415Y1253371D01*
G01X65562Y1256618D02*
X62242Y1253433D01*
G01X65399Y1256688D02*
X62037Y1253464D01*
G01X65225Y1256749D02*
X61825Y1253487D01*
G01X65047Y1256806D02*
X61613Y1253511D01*
G01X64869Y1256862D02*
X61402Y1253536D01*
G01X64691Y1256918D02*
X61189Y1253559D01*
G01X64513Y1256975D02*
X60927Y1253535D01*
G01X64328Y1257025D02*
X60658Y1253504D01*
G01X64135Y1257067D02*
X60388Y1253473D01*
G01X63941Y1257108D02*
X60078Y1253402D01*
G01X63748Y1257150D02*
X59709Y1253276D01*
G01X63555Y1257192D02*
X59341Y1253149D01*
G01X63355Y1257227D02*
X58747Y1252807D01*
G01X77565Y1247541D02*
X77613Y1247815D01*
G01X77421Y1246721D02*
X77469Y1246995D01*
G01X77613Y1247815D02*
X77661Y1248088D01*
G01X77373Y1246449D02*
X77421Y1246721D01*
G01X77516Y1247268D02*
X77565Y1247541D01*
G01X77661Y1248088D02*
X77708Y1248361D01*
G01X77892Y1255581D02*
X77655D01*
G01D02*
X77419D01*
G01X76945D02*
X76708D01*
G01X77419D02*
X77182D01*
G01D02*
X76945D01*
G01X75050D02*
X74813D01*
G01X76708D02*
X76471D01*
G01X74813D02*
X74577D01*
G01X75287D02*
X75050D01*
G01X76471D02*
X76235D01*
G01D02*
X75997D01*
G01D02*
X75761D01*
G01X75524D02*
X75287D01*
G01X75761D02*
X75524D01*
G01X77469Y1246995D02*
X77516Y1247268D01*
G01X74293Y1254173D02*
X74341Y1254446D01*
G01X74389Y1254719D02*
X74437Y1254992D01*
G01X74341Y1254446D02*
X74389Y1254719D01*
G01X74245Y1253900D02*
X74293Y1254173D01*
G01X74437Y1254992D02*
X74485Y1255266D01*
G01X74101Y1253080D02*
X74053Y1252807D01*
G01X74197Y1253626D02*
X74245Y1253900D01*
G01X74149Y1253353D02*
X74197Y1253626D01*
G01X74101Y1253080D02*
X74149Y1253353D01*
G01X74577Y1255581D02*
X74540D01*
X74532Y1255539D01*
G01X74053Y1252807D02*
X74005Y1252533D01*
G01X74485Y1255266D02*
X74532Y1255539D01*
G01X73190Y1247889D02*
X73142Y1247616D01*
G01X73333Y1248708D02*
X73286Y1248435D01*
G01D02*
X73238Y1248162D01*
G01X73477Y1249528D02*
X73430Y1249255D01*
G01D02*
X73382Y1248982D01*
G01D02*
X73333Y1248708D01*
G01X73238Y1248162D02*
X73190Y1247889D01*
G01X74005Y1252533D02*
X73957Y1252261D01*
G01X73142Y1247616D02*
X73094Y1247343D01*
G01D02*
X73046Y1247069D01*
G01X73861Y1251714D02*
X73813Y1251440D01*
G01X73525Y1249802D02*
X73477Y1249528D01*
G01X73813Y1251440D02*
X73765Y1251167D01*
G01X73957Y1252261D02*
X73909Y1251987D01*
G01D02*
X73861Y1251714D01*
G01X73765Y1251167D02*
X73717Y1250895D01*
G01X73574Y1250074D02*
X73525Y1249802D01*
G01X73622Y1250348D02*
X73574Y1250074D01*
G01X73717Y1250895D02*
X73669Y1250621D01*
G01D02*
X73622Y1250348D01*
G01X73046Y1247069D02*
X72998Y1246796D01*
G01D02*
X72950Y1246523D01*
G01X91929Y157126D02*
X95886Y204858D01*
G02X107657I5886J-488D01*
G01X111614Y157126D01*
G02X91929I-9842J0D01*
G01Y905157D02*
X95886Y952889D01*
G02X107657I5886J-488D01*
G01X111614Y905157D01*
G02X91929I-9842J0D01*
G01X100557Y1238696D02*
X103535Y1241554D01*
G01X100320Y1238696D02*
X103584Y1241827D01*
G01X100082Y1238696D02*
X103631Y1242100D01*
G01X99845Y1238696D02*
X103679Y1242374D01*
G01X99608Y1238696D02*
X103728Y1242647D01*
G01X99372Y1238696D02*
X103775Y1242920D01*
G01X99135Y1238696D02*
X103823Y1243194D01*
G01X98898Y1238696D02*
X103871Y1243467D01*
G01X98662Y1238696D02*
X103919Y1243739D01*
G01X98628Y1238891D02*
X103966Y1244013D01*
G01X98677Y1239165D02*
X104015Y1244286D01*
G01X98725Y1239439D02*
X104063Y1244559D01*
G01X98774Y1239712D02*
X104110Y1244832D01*
G01X98227Y1239415D02*
X104159Y1245105D01*
G01X97630Y1239070D02*
X104206Y1245379D01*
G01X97156Y1238842D02*
X104254Y1245652D01*
G01X96775Y1238704D02*
X104303Y1245925D01*
G01X96438Y1238608D02*
X104350Y1246198D01*
G01X96101Y1238513D02*
X104398Y1246471D01*
G01X95794Y1238445D02*
X104446Y1246744D01*
G01X95531Y1238421D02*
X104494Y1247018D01*
G01X95267Y1238393D02*
X104541Y1247290D01*
G01X95004Y1238369D02*
X104590Y1247564D01*
G01X94740Y1238342D02*
X104638Y1247838D01*
G01X94513Y1238351D02*
X104685Y1248110D01*
G01X94285Y1238361D02*
X104734Y1248383D01*
G01X104782Y1248657D02*
X94064Y1238376D01*
G01X93853Y1238402D02*
X98411Y1242773D01*
G01X93643Y1238426D02*
X97890Y1242500D01*
G01X93443Y1238461D02*
X97508Y1242361D01*
G01X93248Y1238502D02*
X97134Y1242230D01*
G01X93053Y1238541D02*
X96863Y1242197D01*
G01X92870Y1238594D02*
X96592Y1242163D01*
G01X92690Y1238648D02*
X96321Y1242130D01*
G01X92509Y1238703D02*
X96060Y1242108D01*
G01X92341Y1238768D02*
X95840Y1242124D01*
G01X92175Y1238836D02*
X95620Y1242140D01*
G01X92009Y1238903D02*
X95410Y1242165D01*
G01X91854Y1238982D02*
X95223Y1242214D01*
G01X91702Y1239063D02*
X95037Y1242263D01*
G01X91550Y1239145D02*
X94866Y1242326D01*
G01X91407Y1239235D02*
X94713Y1242406D01*
G01X91269Y1239329D02*
X94560Y1242487D01*
G01X91131Y1239424D02*
X94433Y1242593D01*
G01X91000Y1239526D02*
X94313Y1242705D01*
G01X90876Y1239634D02*
X94203Y1242826D01*
G01X90752Y1239742D02*
X94117Y1242970D01*
G01X90632Y1239855D02*
X94030Y1243115D01*
G01X90522Y1239977D02*
X93977Y1243290D01*
G01X90413Y1240099D02*
X93925Y1243468D01*
G01X90305Y1240222D02*
X93903Y1243674D01*
G01X90211Y1240360D02*
X93888Y1243887D01*
G01X90117Y1240497D02*
X93908Y1244133D01*
G01X90023Y1240634D02*
X93944Y1244395D01*
G01X89943Y1240784D02*
X94069Y1244742D01*
G01X89865Y1240937D02*
X94195Y1245090D01*
G01X89788Y1241090D02*
X98877Y1249808D01*
G01X89721Y1241253D02*
X98677Y1249844D01*
G01X86108Y1238696D02*
X86227Y1238810D01*
G01X85871Y1238696D02*
X86276Y1239084D01*
G01X85634Y1238696D02*
X86323Y1239357D01*
G01X85397Y1238696D02*
X86371Y1239630D01*
G01X85161Y1238696D02*
X86419Y1239903D01*
G01X84923Y1238696D02*
X86468Y1240177D01*
G01X84687Y1238696D02*
X86516Y1240450D01*
G01X84450Y1238696D02*
X86563Y1240723D01*
G01X84213Y1238696D02*
X86611Y1240996D01*
G01X83977Y1238696D02*
X86659Y1241270D01*
G01X83739Y1238696D02*
X86708Y1241544D01*
G01X83503Y1238696D02*
X86756Y1241816D01*
G01X83266Y1238696D02*
X86803Y1242089D01*
G01X83029Y1238696D02*
X86851Y1242363D01*
G01X82792Y1238696D02*
X86900Y1242636D01*
G01X82555Y1238696D02*
X86948Y1242909D01*
G01X82319Y1238696D02*
X86996Y1243183D01*
G01X82082Y1238696D02*
X87043Y1243456D01*
G01X81844Y1238696D02*
X87091Y1243729D01*
G01X81802Y1238882D02*
X87140Y1244003D01*
G01X81850Y1239156D02*
X87188Y1244276D01*
G01X81897Y1239428D02*
X87236Y1244549D01*
G01X81946Y1239702D02*
X87283Y1244822D01*
G01X81442Y1239445D02*
X87332Y1245096D01*
G01X80837Y1239092D02*
X87380Y1245368D01*
G01X80367Y1238869D02*
X87428Y1245642D01*
G01X79980Y1238724D02*
X87476Y1245916D01*
G01X79647Y1238632D02*
X87523Y1246189D01*
G01X79313Y1238540D02*
X87572Y1246462D01*
G01X78990Y1238457D02*
X87620Y1246736D01*
G01X78728Y1238433D02*
X87668Y1247009D01*
G01X78466Y1238408D02*
X87716Y1247282D01*
G01X78204Y1238385D02*
X87764Y1247555D01*
G01X77942Y1238361D02*
X87812Y1247828D01*
G01X77692Y1238347D02*
X87860Y1248102D01*
G01X100557Y1238696D02*
X100793D01*
G01X100320D02*
X100557D01*
G01X99135D02*
X99372D01*
G01X98898D02*
X99135D01*
G01X98628Y1238891D02*
X98594Y1238696D01*
X98662D01*
G01D02*
X98898D01*
G01X98677Y1239165D02*
X98628Y1238891D01*
G01X100082Y1238696D02*
X100320D01*
G01X99608D02*
X99845D01*
G01X99372D02*
X99608D01*
G01X99845D02*
X100082D01*
G01X98774Y1239712D02*
X98725Y1239439D01*
G01D02*
X98677Y1239165D01*
G01X85871Y1238696D02*
X86108D01*
G01X84923D02*
X85161D01*
G01D02*
X85397D01*
G01X84450D02*
X84687D01*
G01D02*
X84923D01*
G01X85634D02*
X85871D01*
G01X85397D02*
X85634D01*
G01X84213D02*
X84450D01*
G01X82082D02*
X82319D01*
G01X83977D02*
X84213D01*
G01X82555D02*
X82792D01*
G01D02*
X83029D01*
G01X82319D02*
X82555D01*
G01X83739D02*
X83977D01*
G01X81844D02*
X82082D01*
G01X83503D02*
X83739D01*
G01X83266D02*
X83503D01*
G01X83029D02*
X83266D01*
G01X81946Y1239702D02*
X81897Y1239428D01*
G01X81850Y1239156D02*
X81802Y1238882D01*
G01X81897Y1239428D02*
X81850Y1239156D01*
G01X81802Y1238882D02*
X81770Y1238696D01*
X81844D01*
G01X86371Y1239630D02*
X86323Y1239357D01*
G01D02*
X86276Y1239084D01*
G01X86419Y1239903D02*
X86371Y1239630D01*
G01X86276Y1239084D02*
X86227Y1238810D01*
G01X86108Y1238696D02*
X86207D01*
X86227Y1238810D01*
G01X86611Y1240996D02*
X86563Y1240723D01*
G01D02*
X86516Y1240450D01*
G01D02*
X86468Y1240177D01*
G01D02*
X86419Y1239903D01*
G01X86659Y1241270D02*
X86611Y1240996D01*
G01X86708Y1241544D02*
X86659Y1241270D01*
G01X100557Y1238696D02*
X103535Y1241554D01*
G01X100320Y1238696D02*
X103584Y1241827D01*
G01X100082Y1238696D02*
X103631Y1242100D01*
G01X99845Y1238696D02*
X103679Y1242374D01*
G01X99608Y1238696D02*
X103728Y1242647D01*
G01X99372Y1238696D02*
X103775Y1242920D01*
G01X99135Y1238696D02*
X103823Y1243194D01*
G01X98898Y1238696D02*
X103871Y1243467D01*
G01X98662Y1238696D02*
X103919Y1243739D01*
G01X98628Y1238891D02*
X103966Y1244013D01*
G01X98677Y1239165D02*
X104015Y1244286D01*
G01X98725Y1239439D02*
X104063Y1244559D01*
G01X98774Y1239712D02*
X104110Y1244832D01*
G01X98227Y1239415D02*
X104159Y1245105D01*
G01X97630Y1239070D02*
X104206Y1245379D01*
G01X97156Y1238842D02*
X104254Y1245652D01*
G01X96775Y1238704D02*
X104303Y1245925D01*
G01X96438Y1238608D02*
X104350Y1246198D01*
G01X96101Y1238513D02*
X104398Y1246471D01*
G01X95794Y1238445D02*
X104446Y1246744D01*
G01X95531Y1238421D02*
X104494Y1247018D01*
G01X95267Y1238393D02*
X104541Y1247290D01*
G01X95004Y1238369D02*
X104590Y1247564D01*
G01X94740Y1238342D02*
X104638Y1247838D01*
G01X94513Y1238351D02*
X104685Y1248110D01*
G01X94285Y1238361D02*
X104734Y1248383D01*
G01X104782Y1248657D02*
X94064Y1238376D01*
G01X93853Y1238402D02*
X98411Y1242773D01*
G01X93643Y1238426D02*
X97890Y1242500D01*
G01X93443Y1238461D02*
X97508Y1242361D01*
G01X93248Y1238502D02*
X97134Y1242230D01*
G01X93053Y1238541D02*
X96863Y1242197D01*
G01X92870Y1238594D02*
X96592Y1242163D01*
G01X92690Y1238648D02*
X96321Y1242130D01*
G01X92509Y1238703D02*
X96060Y1242108D01*
G01X92341Y1238768D02*
X95840Y1242124D01*
G01X92175Y1238836D02*
X95620Y1242140D01*
G01X92009Y1238903D02*
X95410Y1242165D01*
G01X91854Y1238982D02*
X95223Y1242214D01*
G01X91702Y1239063D02*
X95037Y1242263D01*
G01X91550Y1239145D02*
X94866Y1242326D01*
G01X91407Y1239235D02*
X94713Y1242406D01*
G01X91269Y1239329D02*
X94560Y1242487D01*
G01X91131Y1239424D02*
X94433Y1242593D01*
G01X91000Y1239526D02*
X94313Y1242705D01*
G01X90876Y1239634D02*
X94203Y1242826D01*
G01X90752Y1239742D02*
X94117Y1242970D01*
G01X90632Y1239855D02*
X94030Y1243115D01*
G01X90522Y1239977D02*
X93977Y1243290D01*
G01X90413Y1240099D02*
X93925Y1243468D01*
G01X90305Y1240222D02*
X93903Y1243674D01*
G01X90211Y1240360D02*
X93888Y1243887D01*
G01X90117Y1240497D02*
X93908Y1244133D01*
G01X90023Y1240634D02*
X93944Y1244395D01*
G01X89943Y1240784D02*
X94069Y1244742D01*
G01X89865Y1240937D02*
X94195Y1245090D01*
G01X89788Y1241090D02*
X98877Y1249808D01*
G01X89721Y1241253D02*
X98677Y1249844D01*
G01X86108Y1238696D02*
X86227Y1238810D01*
G01X85871Y1238696D02*
X86276Y1239084D01*
G01X85634Y1238696D02*
X86323Y1239357D01*
G01X85397Y1238696D02*
X86371Y1239630D01*
G01X85161Y1238696D02*
X86419Y1239903D01*
G01X84923Y1238696D02*
X86468Y1240177D01*
G01X84687Y1238696D02*
X86516Y1240450D01*
G01X84450Y1238696D02*
X86563Y1240723D01*
G01X84213Y1238696D02*
X86611Y1240996D01*
G01X83977Y1238696D02*
X86659Y1241270D01*
G01X83739Y1238696D02*
X86708Y1241544D01*
G01X83503Y1238696D02*
X86756Y1241816D01*
G01X83266Y1238696D02*
X86803Y1242089D01*
G01X83029Y1238696D02*
X86851Y1242363D01*
G01X82792Y1238696D02*
X86900Y1242636D01*
G01X82555Y1238696D02*
X86948Y1242909D01*
G01X82319Y1238696D02*
X86996Y1243183D01*
G01X82082Y1238696D02*
X87043Y1243456D01*
G01X81844Y1238696D02*
X87091Y1243729D01*
G01X81802Y1238882D02*
X87140Y1244003D01*
G01X81850Y1239156D02*
X87188Y1244276D01*
G01X81897Y1239428D02*
X87236Y1244549D01*
G01X81946Y1239702D02*
X87283Y1244822D01*
G01X81442Y1239445D02*
X87332Y1245096D01*
G01X80837Y1239092D02*
X87380Y1245368D01*
G01X80367Y1238869D02*
X87428Y1245642D01*
G01X79980Y1238724D02*
X87476Y1245916D01*
G01X79647Y1238632D02*
X87523Y1246189D01*
G01X79313Y1238540D02*
X87572Y1246462D01*
G01X78990Y1238457D02*
X87620Y1246736D01*
G01X78728Y1238433D02*
X87668Y1247009D01*
G01X78466Y1238408D02*
X87716Y1247282D01*
G01X78204Y1238385D02*
X87764Y1247555D01*
G01X77942Y1238361D02*
X87812Y1247828D01*
G01X77692Y1238347D02*
X87860Y1248102D01*
G01X100557Y1238696D02*
X100793D01*
G01X100320D02*
X100557D01*
G01X99135D02*
X99372D01*
G01X98898D02*
X99135D01*
G01X98628Y1238891D02*
X98594Y1238696D01*
X98662D01*
G01D02*
X98898D01*
G01X98677Y1239165D02*
X98628Y1238891D01*
G01X100082Y1238696D02*
X100320D01*
G01X99608D02*
X99845D01*
G01X99372D02*
X99608D01*
G01X99845D02*
X100082D01*
G01X98774Y1239712D02*
X98725Y1239439D01*
G01D02*
X98677Y1239165D01*
G01X85871Y1238696D02*
X86108D01*
G01X84923D02*
X85161D01*
G01D02*
X85397D01*
G01X84450D02*
X84687D01*
G01D02*
X84923D01*
G01X85634D02*
X85871D01*
G01X85397D02*
X85634D01*
G01X84213D02*
X84450D01*
G01X82082D02*
X82319D01*
G01X83977D02*
X84213D01*
G01X82555D02*
X82792D01*
G01D02*
X83029D01*
G01X82319D02*
X82555D01*
G01X83739D02*
X83977D01*
G01X81844D02*
X82082D01*
G01X83503D02*
X83739D01*
G01X83266D02*
X83503D01*
G01X83029D02*
X83266D01*
G01X81946Y1239702D02*
X81897Y1239428D01*
G01X81850Y1239156D02*
X81802Y1238882D01*
G01X81897Y1239428D02*
X81850Y1239156D01*
G01X81802Y1238882D02*
X81770Y1238696D01*
X81844D01*
G01X86371Y1239630D02*
X86323Y1239357D01*
G01D02*
X86276Y1239084D01*
G01X86419Y1239903D02*
X86371Y1239630D01*
G01X86276Y1239084D02*
X86227Y1238810D01*
G01X86108Y1238696D02*
X86207D01*
X86227Y1238810D01*
G01X86611Y1240996D02*
X86563Y1240723D01*
G01D02*
X86516Y1240450D01*
G01D02*
X86468Y1240177D01*
G01D02*
X86419Y1239903D01*
G01X86659Y1241270D02*
X86611Y1240996D01*
G01X86708Y1241544D02*
X86659Y1241270D01*
G01X104829Y1248930D02*
X99496Y1243813D01*
G01X104878Y1249203D02*
X99543Y1244086D01*
G01X104925Y1249476D02*
X99591Y1244359D01*
G01X104973Y1249749D02*
X99639Y1244633D01*
G01X105020Y1250023D02*
X99687Y1244906D01*
G01X105041Y1250269D02*
X99735Y1245179D01*
G01X105061Y1250515D02*
X99783Y1245452D01*
G01X105081Y1250762D02*
X99831Y1245726D01*
G01X105100Y1251008D02*
X99721Y1245848D01*
G01X105121Y1251254D02*
X99581Y1245939D01*
G01X105114Y1251475D02*
X99429Y1246021D01*
G01X105087Y1251676D02*
X99273Y1246100D01*
G01X105060Y1251877D02*
X99109Y1246169D01*
G01X105032Y1252078D02*
X98937Y1246231D01*
G01X105004Y1252278D02*
X98758Y1246286D01*
G01X95258Y1246110D02*
X99077Y1249774D01*
G01X89662Y1241423D02*
X98476Y1249878D01*
G01X89602Y1241593D02*
X98264Y1249903D01*
G01X89551Y1241771D02*
X98039Y1249914D01*
G01X89510Y1241959D02*
X97815Y1249926D01*
G01X89470Y1242148D02*
X97590Y1249938D01*
G01X89435Y1242342D02*
X97366Y1249950D01*
G01X89417Y1242551D02*
X97118Y1249939D01*
G01X89398Y1242761D02*
X96865Y1249924D01*
G01X89384Y1242975D02*
X96612Y1249908D01*
G01X89390Y1243207D02*
X96358Y1249892D01*
G01X89395Y1243440D02*
X96105Y1249877D01*
G01X89407Y1243678D02*
X95841Y1249850D01*
G01X89439Y1243937D02*
X95543Y1249792D01*
G01X89473Y1244196D02*
X95245Y1249734D01*
G01X89525Y1244473D02*
X94948Y1249675D01*
G01X89612Y1244784D02*
X94650Y1249617D01*
G01X89699Y1245094D02*
X94295Y1249503D01*
G01X89787Y1245406D02*
X93920Y1249371D01*
G01X89896Y1245738D02*
X93546Y1249239D01*
G01X90134Y1246193D02*
X93095Y1249033D01*
G01X82226Y1243833D02*
X88100Y1249468D01*
G01X82487Y1244310D02*
X88148Y1249741D01*
G01X82665Y1244709D02*
X88196Y1250015D01*
G01X82786Y1245052D02*
X88244Y1250289D01*
G01X88292Y1250561D02*
X82898Y1245387D01*
G01X88340Y1250834D02*
X82963Y1245676D01*
G01X88388Y1251108D02*
X83029Y1245967D01*
G01X88436Y1251381D02*
X83094Y1246257D01*
G01X99543Y1244086D02*
X99496Y1243813D01*
G01X99783Y1245452D02*
X99735Y1245179D01*
G01X99831Y1245726D02*
X99783Y1245452D01*
G01X99687Y1244906D02*
X99639Y1244633D01*
G01D02*
X99591Y1244359D01*
G01X99735Y1245179D02*
X99687Y1244906D01*
G01X99591Y1244359D02*
X99543Y1244086D01*
G01X87283Y1244822D02*
X87332Y1245096D01*
G01X87380Y1245368D02*
X87428Y1245642D01*
G01X87188Y1244276D02*
X87236Y1244549D01*
G01D02*
X87283Y1244822D01*
G01X87332Y1245096D02*
X87380Y1245368D01*
G01X87428Y1245642D02*
X87476Y1245916D01*
G01D02*
X87523Y1246189D01*
G01D02*
X87572Y1246462D01*
G01X86803Y1242089D02*
X86756Y1241816D01*
G01X86900Y1242636D02*
X86851Y1242363D01*
G01D02*
X86803Y1242089D01*
G01X86756Y1241816D02*
X86708Y1241544D01*
G01X86948Y1242909D02*
X86900Y1242636D01*
G01X87091Y1243729D02*
X87043Y1243456D01*
G01X87091Y1243729D02*
X87140Y1244003D01*
G01X86996Y1243183D02*
X86948Y1242909D01*
G01X87043Y1243456D02*
X86996Y1243183D01*
G01X87140Y1244003D02*
X87188Y1244276D01*
G01X104829Y1248930D02*
X99496Y1243813D01*
G01X104878Y1249203D02*
X99543Y1244086D01*
G01X104925Y1249476D02*
X99591Y1244359D01*
G01X104973Y1249749D02*
X99639Y1244633D01*
G01X105020Y1250023D02*
X99687Y1244906D01*
G01X105041Y1250269D02*
X99735Y1245179D01*
G01X105061Y1250515D02*
X99783Y1245452D01*
G01X105081Y1250762D02*
X99831Y1245726D01*
G01X105100Y1251008D02*
X99721Y1245848D01*
G01X105121Y1251254D02*
X99581Y1245939D01*
G01X105114Y1251475D02*
X99429Y1246021D01*
G01X105087Y1251676D02*
X99273Y1246100D01*
G01X105060Y1251877D02*
X99109Y1246169D01*
G01X105032Y1252078D02*
X98937Y1246231D01*
G01X105004Y1252278D02*
X98758Y1246286D01*
G01X95258Y1246110D02*
X99077Y1249774D01*
G01X89662Y1241423D02*
X98476Y1249878D01*
G01X89602Y1241593D02*
X98264Y1249903D01*
G01X89551Y1241771D02*
X98039Y1249914D01*
G01X89510Y1241959D02*
X97815Y1249926D01*
G01X89470Y1242148D02*
X97590Y1249938D01*
G01X89435Y1242342D02*
X97366Y1249950D01*
G01X89417Y1242551D02*
X97118Y1249939D01*
G01X89398Y1242761D02*
X96865Y1249924D01*
G01X89384Y1242975D02*
X96612Y1249908D01*
G01X89390Y1243207D02*
X96358Y1249892D01*
G01X89395Y1243440D02*
X96105Y1249877D01*
G01X89407Y1243678D02*
X95841Y1249850D01*
G01X89439Y1243937D02*
X95543Y1249792D01*
G01X89473Y1244196D02*
X95245Y1249734D01*
G01X89525Y1244473D02*
X94948Y1249675D01*
G01X89612Y1244784D02*
X94650Y1249617D01*
G01X89699Y1245094D02*
X94295Y1249503D01*
G01X89787Y1245406D02*
X93920Y1249371D01*
G01X89896Y1245738D02*
X93546Y1249239D01*
G01X90134Y1246193D02*
X93095Y1249033D01*
G01X82226Y1243833D02*
X88100Y1249468D01*
G01X82487Y1244310D02*
X88148Y1249741D01*
G01X82665Y1244709D02*
X88196Y1250015D01*
G01X82786Y1245052D02*
X88244Y1250289D01*
G01X88292Y1250561D02*
X82898Y1245387D01*
G01X88340Y1250834D02*
X82963Y1245676D01*
G01X88388Y1251108D02*
X83029Y1245967D01*
G01X88436Y1251381D02*
X83094Y1246257D01*
G01X99543Y1244086D02*
X99496Y1243813D01*
G01X99783Y1245452D02*
X99735Y1245179D01*
G01X99831Y1245726D02*
X99783Y1245452D01*
G01X99687Y1244906D02*
X99639Y1244633D01*
G01D02*
X99591Y1244359D01*
G01X99735Y1245179D02*
X99687Y1244906D01*
G01X99591Y1244359D02*
X99543Y1244086D01*
G01X87283Y1244822D02*
X87332Y1245096D01*
G01X87380Y1245368D02*
X87428Y1245642D01*
G01X87188Y1244276D02*
X87236Y1244549D01*
G01D02*
X87283Y1244822D01*
G01X87332Y1245096D02*
X87380Y1245368D01*
G01X87428Y1245642D02*
X87476Y1245916D01*
G01D02*
X87523Y1246189D01*
G01D02*
X87572Y1246462D01*
G01X86803Y1242089D02*
X86756Y1241816D01*
G01X86900Y1242636D02*
X86851Y1242363D01*
G01D02*
X86803Y1242089D01*
G01X86756Y1241816D02*
X86708Y1241544D01*
G01X86948Y1242909D02*
X86900Y1242636D01*
G01X87091Y1243729D02*
X87043Y1243456D01*
G01X87091Y1243729D02*
X87140Y1244003D01*
G01X86996Y1243183D02*
X86948Y1242909D01*
G01X87043Y1243456D02*
X86996Y1243183D01*
G01X87140Y1244003D02*
X87188Y1244276D01*
G01X104977Y1252479D02*
X98568Y1246332D01*
G01X104921Y1252655D02*
X98373Y1246373D01*
G01X104856Y1252817D02*
X98169Y1246403D01*
G01X104788Y1252980D02*
X97960Y1246430D01*
G01X104720Y1253143D02*
X97742Y1246448D01*
G01X104654Y1253306D02*
X97520Y1246463D01*
G01X100295Y1249351D02*
X97293Y1246472D01*
G01X104588Y1253469D02*
X100500Y1249548D01*
G01X100136Y1249426D02*
X97061Y1246477D01*
G01X104505Y1253617D02*
X100547Y1249821D01*
G01X104403Y1253747D02*
X100594Y1250094D01*
G01X99977Y1249500D02*
X96821Y1246473D01*
G01X99806Y1249565D02*
X96549Y1246439D01*
G01X104303Y1253877D02*
X100620Y1250345D01*
G01X104201Y1254007D02*
X100634Y1250586D01*
G01X96276Y1246405D02*
X99628Y1249621D01*
G01X96004Y1246371D02*
X99450Y1249677D01*
G01X104099Y1254137D02*
X100613Y1250792D01*
G01X95723Y1246329D02*
X99271Y1249733D01*
G01X103999Y1254267D02*
X100583Y1250991D01*
G01X103896Y1254398D02*
X100525Y1251163D01*
G01X103764Y1254497D02*
X100464Y1251331D01*
G01X103633Y1254598D02*
X100373Y1251471D01*
G01X103500Y1254698D02*
X100281Y1251610D01*
G01X103367Y1254798D02*
X100165Y1251726D01*
G01X103234Y1254898D02*
X100042Y1251835D01*
G01X103102Y1254998D02*
X99907Y1251933D01*
G01X102960Y1255088D02*
X99754Y1252013D01*
G01X102797Y1255160D02*
X99600Y1252093D01*
G01X102634Y1255232D02*
X99417Y1252145D01*
G01X102473Y1255304D02*
X99232Y1252194D01*
G01X102311Y1255375D02*
X99033Y1252231D01*
G01X102149Y1255447D02*
X98814Y1252248D01*
G01X101987Y1255519D02*
X98595Y1252265D01*
G01X101806Y1255572D02*
X98357Y1252263D01*
G01X101614Y1255616D02*
X98114Y1252259D01*
G01X101423Y1255660D02*
X97872Y1252254D01*
G01X101232Y1255704D02*
X97619Y1252238D01*
G01X101041Y1255748D02*
X97365Y1252221D01*
G01X100849Y1255791D02*
X97103Y1252198D01*
G01X100658Y1255835D02*
X96830Y1252162D01*
G01X100437Y1255850D02*
X96553Y1252124D01*
G01X100217Y1255865D02*
X96254Y1252064D01*
G01X99995Y1255880D02*
X95946Y1251996D01*
G01X90372Y1246649D02*
X92543Y1248731D01*
G01X99774Y1255896D02*
X95613Y1251904D01*
G01X99553Y1255911D02*
X95257Y1251789D01*
G01X99332Y1255925D02*
X94878Y1251652D01*
G01X99100Y1255931D02*
X94456Y1251475D01*
G01X98856Y1255924D02*
X94000Y1251265D01*
G01X98612Y1255917D02*
X93710Y1251214D01*
G01X98369Y1255911D02*
X93647Y1251381D01*
G01X98117Y1255897D02*
X93584Y1251548D01*
G01X97856Y1255873D02*
X93521Y1251715D01*
G01X97595Y1255850D02*
X93459Y1251882D01*
G01X97335Y1255827D02*
X93396Y1252049D01*
G01X97051Y1255783D02*
X93333Y1252216D01*
G01X96767Y1255738D02*
X93270Y1252383D01*
G01X96483Y1255692D02*
X93207Y1252550D01*
G01X96171Y1255620D02*
X93144Y1252716D01*
G01X95857Y1255547D02*
X93082Y1252883D01*
G01X95529Y1255459D02*
X93019Y1253051D01*
G01X95179Y1255350D02*
X92956Y1253218D01*
G01X94820Y1255232D02*
X92893Y1253384D01*
G01X94425Y1255081D02*
X92830Y1253551D01*
G01X94016Y1254916D02*
X92767Y1253719D01*
G01X93572Y1254718D02*
X92705Y1253885D01*
G01X93101Y1254492D02*
X92642Y1254052D01*
G01X92604Y1254243D02*
X92579Y1254219D01*
G01X88484Y1251654D02*
X83147Y1246535D01*
G01X88532Y1251927D02*
X83195Y1246808D01*
G01X88580Y1252201D02*
X83243Y1247081D01*
G01X88628Y1252474D02*
X83291Y1247355D01*
G01X88676Y1252748D02*
X83339Y1247627D01*
G01X88724Y1253020D02*
X83387Y1247900D01*
G01X88772Y1253294D02*
X83435Y1248174D01*
G01X88820Y1253567D02*
X83483Y1248447D01*
G01X88868Y1253841D02*
X83530Y1248720D01*
G01X88916Y1254113D02*
X83578Y1248993D01*
G01X88965Y1254387D02*
X83626Y1249266D01*
G01X89013Y1254661D02*
X83674Y1249540D01*
G01X89060Y1254934D02*
X83722Y1249812D01*
G01X89108Y1255207D02*
X83770Y1250085D01*
G01X89156Y1255480D02*
X83818Y1250359D01*
G01X89024Y1255581D02*
X83865Y1250632D01*
G01X88788Y1255581D02*
X83914Y1250905D01*
G01X88551Y1255581D02*
X83961Y1251178D01*
G01X88314Y1255581D02*
X84009Y1251451D01*
G01X88077Y1255581D02*
X84057Y1251725D01*
G01X87840Y1255581D02*
X84105Y1251998D01*
G01X87603Y1255581D02*
X84153Y1252270D01*
G01X87367Y1255581D02*
X84200Y1252544D01*
G01X87129Y1255581D02*
X84249Y1252817D01*
G01X86893Y1255581D02*
X84296Y1253090D01*
G01X86656Y1255581D02*
X84344Y1253363D01*
G01X86419Y1255581D02*
X84392Y1253636D01*
G01X86182Y1255581D02*
X84440Y1253910D01*
G01X85945Y1255581D02*
X84488Y1254183D01*
G01X85709Y1255581D02*
X84535Y1254455D01*
G01X85472Y1255581D02*
X84584Y1254729D01*
G01X85235Y1255581D02*
X84632Y1255002D01*
G01X84998Y1255581D02*
X84679Y1255275D01*
G01X84761Y1255581D02*
X84727Y1255548D01*
G01X92767Y1253719D02*
X92705Y1253885D01*
G01X92767Y1253719D02*
X92830Y1253551D01*
G01X92705Y1253885D02*
X92642Y1254052D01*
G01D02*
X92579Y1254219D01*
G01X92830Y1253551D02*
X92893Y1253384D01*
G01X93019Y1253051D02*
X93082Y1252883D01*
G01X92956Y1253218D02*
X93019Y1253051D01*
G01X92893Y1253384D02*
X92956Y1253218D01*
G01X93082Y1252883D02*
X93144Y1252716D01*
G01X93647Y1251381D02*
X93710Y1251214D01*
G01X93333Y1252216D02*
X93396Y1252049D01*
G01X93270Y1252383D02*
X93333Y1252216D01*
G01X93207Y1252550D02*
X93270Y1252383D01*
G01X93396Y1252049D02*
X93459Y1251882D01*
G01X93584Y1251548D02*
X93647Y1251381D01*
G01X93144Y1252716D02*
X93207Y1252550D01*
G01X93459Y1251882D02*
X93521Y1251715D01*
G01D02*
X93584Y1251548D01*
G01X100547Y1249821D02*
X100500Y1249548D01*
G01X100594Y1250094D02*
X100547Y1249821D01*
G01X83914Y1250905D02*
X83865Y1250632D01*
G01X88148Y1249741D02*
X88196Y1250015D01*
G01X88100Y1249468D02*
X88148Y1249741D01*
G01X87668Y1247009D02*
X87716Y1247282D01*
G01X87764Y1247555D02*
X87812Y1247828D01*
G01X87716Y1247282D02*
X87764Y1247555D01*
G01X88052Y1249195D02*
X88004Y1248921D01*
G01X87860Y1248102D02*
X87908Y1248375D01*
G01X88004Y1248921D02*
X87956Y1248648D01*
G01X87908Y1248375D02*
X87956Y1248648D01*
G01X77756Y1248634D02*
X77805Y1248907D01*
G01X77708Y1248361D02*
X77756Y1248634D01*
G01X87812Y1247828D02*
X87860Y1248102D01*
G01X87603Y1255581D02*
X87367D01*
G01X87840D02*
X87603D01*
G01X87129D02*
X86893D01*
G01D02*
X86656D01*
G01X88052Y1249195D02*
X88100Y1249468D01*
G01X88788Y1255581D02*
X88551D01*
G01X88077D02*
X87840D01*
G01X88551D02*
X88314D01*
G01D02*
X88077D01*
G01X85709D02*
X85472D01*
G01D02*
X85235D01*
G01D02*
X84998D01*
G01X77852Y1249180D02*
X77900Y1249454D01*
G01X84998Y1255581D02*
X84761D01*
G01X77900Y1249454D02*
X77948Y1249727D01*
G01X86419Y1255581D02*
X86182D01*
G01X85945D02*
X85709D01*
G01X89024D02*
X88788D01*
G01X86182D02*
X85945D01*
G01X86656D02*
X86419D01*
G01X88484Y1251654D02*
X88532Y1251927D01*
G01X88436Y1251381D02*
X88484Y1251654D01*
G01X88628Y1252474D02*
X88676Y1252748D01*
G01X89156Y1255480D02*
X89174Y1255581D01*
X89024D01*
G01X88580Y1252201D02*
X88628Y1252474D01*
G01X88244Y1250289D02*
X88292Y1250561D01*
G01X88340Y1250834D02*
X88388Y1251108D01*
G01D02*
X88436Y1251381D01*
G01X88292Y1250561D02*
X88340Y1250834D01*
G01X88532Y1251927D02*
X88580Y1252201D01*
G01X88965Y1254387D02*
X89013Y1254661D01*
G01D02*
X89060Y1254934D01*
G01X88676Y1252748D02*
X88724Y1253020D01*
G01X89060Y1254934D02*
X89108Y1255207D01*
G01D02*
X89156Y1255480D01*
G01X88772Y1253294D02*
X88820Y1253567D01*
G01X88724Y1253020D02*
X88772Y1253294D01*
G01X88916Y1254113D02*
X88965Y1254387D01*
G01X88868Y1253841D02*
X88916Y1254113D01*
G01X88820Y1253567D02*
X88868Y1253841D01*
G01X87367Y1255581D02*
X87129D01*
G01X78840D02*
X78603D01*
G01D02*
X78366D01*
G01X78129D02*
X77892D01*
G01X78366D02*
X78129D01*
G01X78955Y1255464D02*
X78976Y1255581D01*
X78840D01*
G01X78236Y1251366D02*
X78284Y1251639D01*
G01X77948Y1249727D02*
X77997Y1250000D01*
G01X78332Y1251913D02*
X78380Y1252186D01*
G01X78188Y1251093D02*
X78236Y1251366D01*
G01X78284Y1251639D02*
X78332Y1251913D01*
G01X78140Y1250820D02*
X78188Y1251093D01*
G01X77997Y1250000D02*
X78044Y1250274D01*
G01X78907Y1255192D02*
X78955Y1255464D01*
G01X78092Y1250547D02*
X78140Y1250820D01*
G01X78380Y1252186D02*
X78428Y1252459D01*
G01X78044Y1250274D02*
X78092Y1250547D01*
G01X78764Y1254371D02*
X78812Y1254645D01*
G01X78715Y1254098D02*
X78764Y1254371D01*
G01X78859Y1254918D02*
X78907Y1255192D01*
G01X78812Y1254645D02*
X78859Y1254918D01*
G01X78524Y1253005D02*
X78572Y1253279D01*
G01X78428Y1252459D02*
X78476Y1252733D01*
G01D02*
X78524Y1253005D01*
G01X78620Y1253552D02*
X78668Y1253826D01*
G01D02*
X78715Y1254098D01*
G01X78572Y1253279D02*
X78620Y1253552D01*
G01X87620Y1246736D02*
X87668Y1247009D01*
G01X83243Y1247081D02*
X83195Y1246808D01*
G01X88244Y1250289D02*
X88196Y1250015D01*
G01X83195Y1246808D02*
X83147Y1246535D01*
G01X83291Y1247355D02*
X83243Y1247081D01*
G01X87572Y1246462D02*
X87620Y1246736D01*
G01X83722Y1249812D02*
X83674Y1249540D01*
G01X83339Y1247627D02*
X83291Y1247355D01*
G01X84679Y1255275D02*
X84727Y1255548D01*
G01X84584Y1254729D02*
X84632Y1255002D01*
G01X84761Y1255581D02*
X84733D01*
X84727Y1255548D01*
G01X84392Y1253636D02*
X84440Y1253910D01*
G01X77852Y1249180D02*
X77805Y1248907D01*
G01X84488Y1254183D02*
X84535Y1254455D01*
G01D02*
X84584Y1254729D01*
G01X84440Y1253910D02*
X84488Y1254183D01*
G01X84344Y1253363D02*
X84392Y1253636D01*
G01X84632Y1255002D02*
X84679Y1255275D01*
G01X83674Y1249540D02*
X83626Y1249266D01*
G01X83818Y1250359D02*
X83770Y1250085D01*
G01X83626Y1249266D02*
X83578Y1248993D01*
G01X83770Y1250085D02*
X83722Y1249812D01*
G01X83435Y1248174D02*
X83387Y1247900D01*
G01D02*
X83339Y1247627D01*
G01X83578Y1248993D02*
X83530Y1248720D01*
G01X83483Y1248447D02*
X83435Y1248174D01*
G01X83530Y1248720D02*
X83483Y1248447D01*
G01X84296Y1253090D02*
X84344Y1253363D01*
G01X84153Y1252270D02*
X84105Y1251998D01*
G01X84200Y1252544D02*
X84153Y1252270D01*
G01X84249Y1252817D02*
X84296Y1253090D01*
G01X84249Y1252817D02*
X84200Y1252544D01*
G01X84057Y1251725D02*
X84009Y1251451D01*
G01X83865Y1250632D02*
X83818Y1250359D01*
G01X83961Y1251178D02*
X83914Y1250905D01*
G01X84009Y1251451D02*
X83961Y1251178D01*
G01X84105Y1251998D02*
X84057Y1251725D01*
G01X104977Y1252479D02*
X98568Y1246332D01*
G01X104921Y1252655D02*
X98373Y1246373D01*
G01X104856Y1252817D02*
X98169Y1246403D01*
G01X104788Y1252980D02*
X97960Y1246430D01*
G01X104720Y1253143D02*
X97742Y1246448D01*
G01X104654Y1253306D02*
X97520Y1246463D01*
G01X100295Y1249351D02*
X97293Y1246472D01*
G01X104588Y1253469D02*
X100500Y1249548D01*
G01X100136Y1249426D02*
X97061Y1246477D01*
G01X104505Y1253617D02*
X100547Y1249821D01*
G01X104403Y1253747D02*
X100594Y1250094D01*
G01X99977Y1249500D02*
X96821Y1246473D01*
G01X99806Y1249565D02*
X96549Y1246439D01*
G01X104303Y1253877D02*
X100620Y1250345D01*
G01X104201Y1254007D02*
X100634Y1250586D01*
G01X96276Y1246405D02*
X99628Y1249621D01*
G01X96004Y1246371D02*
X99450Y1249677D01*
G01X104099Y1254137D02*
X100613Y1250792D01*
G01X95723Y1246329D02*
X99271Y1249733D01*
G01X103999Y1254267D02*
X100583Y1250991D01*
G01X103896Y1254398D02*
X100525Y1251163D01*
G01X103764Y1254497D02*
X100464Y1251331D01*
G01X103633Y1254598D02*
X100373Y1251471D01*
G01X103500Y1254698D02*
X100281Y1251610D01*
G01X103367Y1254798D02*
X100165Y1251726D01*
G01X103234Y1254898D02*
X100042Y1251835D01*
G01X103102Y1254998D02*
X99907Y1251933D01*
G01X102960Y1255088D02*
X99754Y1252013D01*
G01X102797Y1255160D02*
X99600Y1252093D01*
G01X102634Y1255232D02*
X99417Y1252145D01*
G01X102473Y1255304D02*
X99232Y1252194D01*
G01X102311Y1255375D02*
X99033Y1252231D01*
G01X102149Y1255447D02*
X98814Y1252248D01*
G01X101987Y1255519D02*
X98595Y1252265D01*
G01X101806Y1255572D02*
X98357Y1252263D01*
G01X101614Y1255616D02*
X98114Y1252259D01*
G01X101423Y1255660D02*
X97872Y1252254D01*
G01X101232Y1255704D02*
X97619Y1252238D01*
G01X101041Y1255748D02*
X97365Y1252221D01*
G01X100849Y1255791D02*
X97103Y1252198D01*
G01X100658Y1255835D02*
X96830Y1252162D01*
G01X100437Y1255850D02*
X96553Y1252124D01*
G01X100217Y1255865D02*
X96254Y1252064D01*
G01X99995Y1255880D02*
X95946Y1251996D01*
G01X90372Y1246649D02*
X92543Y1248731D01*
G01X99774Y1255896D02*
X95613Y1251904D01*
G01X99553Y1255911D02*
X95257Y1251789D01*
G01X99332Y1255925D02*
X94878Y1251652D01*
G01X99100Y1255931D02*
X94456Y1251475D01*
G01X98856Y1255924D02*
X94000Y1251265D01*
G01X98612Y1255917D02*
X93710Y1251214D01*
G01X98369Y1255911D02*
X93647Y1251381D01*
G01X98117Y1255897D02*
X93584Y1251548D01*
G01X97856Y1255873D02*
X93521Y1251715D01*
G01X97595Y1255850D02*
X93459Y1251882D01*
G01X97335Y1255827D02*
X93396Y1252049D01*
G01X97051Y1255783D02*
X93333Y1252216D01*
G01X96767Y1255738D02*
X93270Y1252383D01*
G01X96483Y1255692D02*
X93207Y1252550D01*
G01X96171Y1255620D02*
X93144Y1252716D01*
G01X95857Y1255547D02*
X93082Y1252883D01*
G01X95529Y1255459D02*
X93019Y1253051D01*
G01X95179Y1255350D02*
X92956Y1253218D01*
G01X94820Y1255232D02*
X92893Y1253384D01*
G01X94425Y1255081D02*
X92830Y1253551D01*
G01X94016Y1254916D02*
X92767Y1253719D01*
G01X93572Y1254718D02*
X92705Y1253885D01*
G01X93101Y1254492D02*
X92642Y1254052D01*
G01X92604Y1254243D02*
X92579Y1254219D01*
G01X88484Y1251654D02*
X83147Y1246535D01*
G01X88532Y1251927D02*
X83195Y1246808D01*
G01X88580Y1252201D02*
X83243Y1247081D01*
G01X88628Y1252474D02*
X83291Y1247355D01*
G01X88676Y1252748D02*
X83339Y1247627D01*
G01X88724Y1253020D02*
X83387Y1247900D01*
G01X88772Y1253294D02*
X83435Y1248174D01*
G01X88820Y1253567D02*
X83483Y1248447D01*
G01X88868Y1253841D02*
X83530Y1248720D01*
G01X88916Y1254113D02*
X83578Y1248993D01*
G01X88965Y1254387D02*
X83626Y1249266D01*
G01X89013Y1254661D02*
X83674Y1249540D01*
G01X89060Y1254934D02*
X83722Y1249812D01*
G01X89108Y1255207D02*
X83770Y1250085D01*
G01X89156Y1255480D02*
X83818Y1250359D01*
G01X89024Y1255581D02*
X83865Y1250632D01*
G01X88788Y1255581D02*
X83914Y1250905D01*
G01X88551Y1255581D02*
X83961Y1251178D01*
G01X88314Y1255581D02*
X84009Y1251451D01*
G01X88077Y1255581D02*
X84057Y1251725D01*
G01X87840Y1255581D02*
X84105Y1251998D01*
G01X87603Y1255581D02*
X84153Y1252270D01*
G01X87367Y1255581D02*
X84200Y1252544D01*
G01X87129Y1255581D02*
X84249Y1252817D01*
G01X86893Y1255581D02*
X84296Y1253090D01*
G01X86656Y1255581D02*
X84344Y1253363D01*
G01X86419Y1255581D02*
X84392Y1253636D01*
G01X86182Y1255581D02*
X84440Y1253910D01*
G01X85945Y1255581D02*
X84488Y1254183D01*
G01X85709Y1255581D02*
X84535Y1254455D01*
G01X85472Y1255581D02*
X84584Y1254729D01*
G01X85235Y1255581D02*
X84632Y1255002D01*
G01X84998Y1255581D02*
X84679Y1255275D01*
G01X84761Y1255581D02*
X84727Y1255548D01*
G01X92767Y1253719D02*
X92705Y1253885D01*
G01X92767Y1253719D02*
X92830Y1253551D01*
G01X92705Y1253885D02*
X92642Y1254052D01*
G01D02*
X92579Y1254219D01*
G01X92830Y1253551D02*
X92893Y1253384D01*
G01X93019Y1253051D02*
X93082Y1252883D01*
G01X92956Y1253218D02*
X93019Y1253051D01*
G01X92893Y1253384D02*
X92956Y1253218D01*
G01X93082Y1252883D02*
X93144Y1252716D01*
G01X93647Y1251381D02*
X93710Y1251214D01*
G01X93333Y1252216D02*
X93396Y1252049D01*
G01X93270Y1252383D02*
X93333Y1252216D01*
G01X93207Y1252550D02*
X93270Y1252383D01*
G01X93396Y1252049D02*
X93459Y1251882D01*
G01X93584Y1251548D02*
X93647Y1251381D01*
G01X93144Y1252716D02*
X93207Y1252550D01*
G01X93459Y1251882D02*
X93521Y1251715D01*
G01D02*
X93584Y1251548D01*
G01X100547Y1249821D02*
X100500Y1249548D01*
G01X100594Y1250094D02*
X100547Y1249821D01*
G01X83914Y1250905D02*
X83865Y1250632D01*
G01X88148Y1249741D02*
X88196Y1250015D01*
G01X88100Y1249468D02*
X88148Y1249741D01*
G01X87668Y1247009D02*
X87716Y1247282D01*
G01X87764Y1247555D02*
X87812Y1247828D01*
G01X87716Y1247282D02*
X87764Y1247555D01*
G01X88052Y1249195D02*
X88004Y1248921D01*
G01X87860Y1248102D02*
X87908Y1248375D01*
G01X88004Y1248921D02*
X87956Y1248648D01*
G01X87908Y1248375D02*
X87956Y1248648D01*
G01X77756Y1248634D02*
X77805Y1248907D01*
G01X77708Y1248361D02*
X77756Y1248634D01*
G01X87812Y1247828D02*
X87860Y1248102D01*
G01X87603Y1255581D02*
X87367D01*
G01X87840D02*
X87603D01*
G01X87129D02*
X86893D01*
G01D02*
X86656D01*
G01X88052Y1249195D02*
X88100Y1249468D01*
G01X88788Y1255581D02*
X88551D01*
G01X88077D02*
X87840D01*
G01X88551D02*
X88314D01*
G01D02*
X88077D01*
G01X85709D02*
X85472D01*
G01D02*
X85235D01*
G01D02*
X84998D01*
G01X77852Y1249180D02*
X77900Y1249454D01*
G01X84998Y1255581D02*
X84761D01*
G01X77900Y1249454D02*
X77948Y1249727D01*
G01X86419Y1255581D02*
X86182D01*
G01X85945D02*
X85709D01*
G01X89024D02*
X88788D01*
G01X86182D02*
X85945D01*
G01X86656D02*
X86419D01*
G01X88484Y1251654D02*
X88532Y1251927D01*
G01X88436Y1251381D02*
X88484Y1251654D01*
G01X88628Y1252474D02*
X88676Y1252748D01*
G01X89156Y1255480D02*
X89174Y1255581D01*
X89024D01*
G01X88580Y1252201D02*
X88628Y1252474D01*
G01X88244Y1250289D02*
X88292Y1250561D01*
G01X88340Y1250834D02*
X88388Y1251108D01*
G01D02*
X88436Y1251381D01*
G01X88292Y1250561D02*
X88340Y1250834D01*
G01X88532Y1251927D02*
X88580Y1252201D01*
G01X88965Y1254387D02*
X89013Y1254661D01*
G01D02*
X89060Y1254934D01*
G01X88676Y1252748D02*
X88724Y1253020D01*
G01X89060Y1254934D02*
X89108Y1255207D01*
G01D02*
X89156Y1255480D01*
G01X88772Y1253294D02*
X88820Y1253567D01*
G01X88724Y1253020D02*
X88772Y1253294D01*
G01X88916Y1254113D02*
X88965Y1254387D01*
G01X88868Y1253841D02*
X88916Y1254113D01*
G01X88820Y1253567D02*
X88868Y1253841D01*
G01X87367Y1255581D02*
X87129D01*
G01X78840D02*
X78603D01*
G01D02*
X78366D01*
G01X78129D02*
X77892D01*
G01X78366D02*
X78129D01*
G01X78955Y1255464D02*
X78976Y1255581D01*
X78840D01*
G01X78236Y1251366D02*
X78284Y1251639D01*
G01X77948Y1249727D02*
X77997Y1250000D01*
G01X78332Y1251913D02*
X78380Y1252186D01*
G01X78188Y1251093D02*
X78236Y1251366D01*
G01X78284Y1251639D02*
X78332Y1251913D01*
G01X78140Y1250820D02*
X78188Y1251093D01*
G01X77997Y1250000D02*
X78044Y1250274D01*
G01X78907Y1255192D02*
X78955Y1255464D01*
G01X78092Y1250547D02*
X78140Y1250820D01*
G01X78380Y1252186D02*
X78428Y1252459D01*
G01X78044Y1250274D02*
X78092Y1250547D01*
G01X78764Y1254371D02*
X78812Y1254645D01*
G01X78715Y1254098D02*
X78764Y1254371D01*
G01X78859Y1254918D02*
X78907Y1255192D01*
G01X78812Y1254645D02*
X78859Y1254918D01*
G01X78524Y1253005D02*
X78572Y1253279D01*
G01X78428Y1252459D02*
X78476Y1252733D01*
G01D02*
X78524Y1253005D01*
G01X78620Y1253552D02*
X78668Y1253826D01*
G01D02*
X78715Y1254098D01*
G01X78572Y1253279D02*
X78620Y1253552D01*
G01X87620Y1246736D02*
X87668Y1247009D01*
G01X83243Y1247081D02*
X83195Y1246808D01*
G01X88244Y1250289D02*
X88196Y1250015D01*
G01X83195Y1246808D02*
X83147Y1246535D01*
G01X83291Y1247355D02*
X83243Y1247081D01*
G01X87572Y1246462D02*
X87620Y1246736D01*
G01X83722Y1249812D02*
X83674Y1249540D01*
G01X83339Y1247627D02*
X83291Y1247355D01*
G01X84679Y1255275D02*
X84727Y1255548D01*
G01X84584Y1254729D02*
X84632Y1255002D01*
G01X84761Y1255581D02*
X84733D01*
X84727Y1255548D01*
G01X84392Y1253636D02*
X84440Y1253910D01*
G01X77852Y1249180D02*
X77805Y1248907D01*
G01X84488Y1254183D02*
X84535Y1254455D01*
G01D02*
X84584Y1254729D01*
G01X84440Y1253910D02*
X84488Y1254183D01*
G01X84344Y1253363D02*
X84392Y1253636D01*
G01X84632Y1255002D02*
X84679Y1255275D01*
G01X83674Y1249540D02*
X83626Y1249266D01*
G01X83818Y1250359D02*
X83770Y1250085D01*
G01X83626Y1249266D02*
X83578Y1248993D01*
G01X83770Y1250085D02*
X83722Y1249812D01*
G01X83435Y1248174D02*
X83387Y1247900D01*
G01D02*
X83339Y1247627D01*
G01X83578Y1248993D02*
X83530Y1248720D01*
G01X83483Y1248447D02*
X83435Y1248174D01*
G01X83530Y1248720D02*
X83483Y1248447D01*
G01X84296Y1253090D02*
X84344Y1253363D01*
G01X84153Y1252270D02*
X84105Y1251998D01*
G01X84200Y1252544D02*
X84153Y1252270D01*
G01X84249Y1252817D02*
X84296Y1253090D01*
G01X84249Y1252817D02*
X84200Y1252544D01*
G01X84057Y1251725D02*
X84009Y1251451D01*
G01X83865Y1250632D02*
X83818Y1250359D01*
G01X83961Y1251178D02*
X83914Y1250905D01*
G01X84009Y1251451D02*
X83961Y1251178D01*
G01X84105Y1251998D02*
X84057Y1251725D01*
G01X89173Y1287047D02*
G02X114370I12599J0D01*
G02X89173I-12599J0D01*
G01X110268Y1238696D02*
X110330Y1238757D01*
G01X110031Y1238696D02*
X110378Y1239030D01*
G01X109793Y1238696D02*
X110425Y1239302D01*
G01X109557Y1238696D02*
X110474Y1239576D01*
G01X109320Y1238696D02*
X110523Y1239850D01*
G01X109082Y1238696D02*
X110570Y1240123D01*
G01X108846Y1238696D02*
X110618Y1240396D01*
G01X108609Y1238696D02*
X110667Y1240669D01*
G01X108372Y1238696D02*
X110715Y1240943D01*
G01X108136Y1238696D02*
X110763Y1241216D01*
G01X107900Y1238696D02*
X110810Y1241489D01*
G01X107661Y1238696D02*
X110859Y1241763D01*
G01X107425Y1238696D02*
X110907Y1242037D01*
G01X107189Y1238696D02*
X110954Y1242309D01*
G01X106952Y1238696D02*
X111003Y1242582D01*
G01X106714Y1238696D02*
X111052Y1242856D01*
G01X106477Y1238696D02*
X111099Y1243130D01*
G01X106241Y1238696D02*
X111147Y1243403D01*
G01X106004Y1238696D02*
X111196Y1243676D01*
G01X105905Y1238827D02*
X111244Y1243950D01*
G01X105952Y1239101D02*
X111292Y1244223D01*
G01X106001Y1239374D02*
X111339Y1244496D01*
G01X106048Y1239647D02*
X111388Y1244769D01*
G01X106096Y1239921D02*
X111436Y1245043D01*
G01X106145Y1240195D02*
X111483Y1245316D01*
G01X106192Y1240467D02*
X111532Y1245589D01*
G01X106240Y1240740D02*
X111581Y1245863D01*
G01X106288Y1241014D02*
X111628Y1246136D01*
G01X106337Y1241287D02*
X111676Y1246410D01*
G01X102925Y1238696D02*
X103058Y1238822D01*
G01X102687Y1238696D02*
X103105Y1239096D01*
G01X102451Y1238696D02*
X103153Y1239369D01*
G01X102215Y1238696D02*
X103201Y1239642D01*
G01X101977Y1238696D02*
X103247Y1239915D01*
G01X101740Y1238696D02*
X103296Y1240189D01*
G01X101503Y1238696D02*
X103345Y1240462D01*
G01X101267Y1238696D02*
X103391Y1240734D01*
G01X101030Y1238696D02*
X103440Y1241008D01*
G01X100793Y1238696D02*
X103489Y1241281D01*
G01X110523Y1239850D02*
X110474Y1239576D01*
G01X110763Y1241216D02*
X110810Y1241489D01*
G01X110618Y1240396D02*
X110570Y1240123D01*
G01X110474Y1239576D02*
X110425Y1239302D01*
G01X110570Y1240123D02*
X110523Y1239850D01*
G01X110715Y1240943D02*
X110667Y1240669D01*
G01X110763Y1241216D02*
X110715Y1240943D01*
G01X110667Y1240669D02*
X110618Y1240396D01*
G01X106337Y1241287D02*
X106288Y1241014D01*
G01X106383Y1241560D02*
X106337Y1241287D01*
G01X106288Y1241014D02*
X106240Y1240740D01*
G01D02*
X106192Y1240467D01*
G01X110031Y1238696D02*
X110268D01*
G01X109557D02*
X109793D01*
G01D02*
X110031D01*
G01X109320D02*
X109557D01*
G01X109082D02*
X109320D01*
G01X106001Y1239374D02*
X105952Y1239101D01*
G01X106241Y1238696D02*
X106477D01*
G01X108846D02*
X109082D01*
G01X105905Y1238827D02*
X105881Y1238696D01*
X106004D01*
G01X105952Y1239101D02*
X105905Y1238827D01*
G01X106192Y1240467D02*
X106145Y1240195D01*
G01D02*
X106096Y1239921D01*
G01D02*
X106048Y1239647D01*
G01D02*
X106001Y1239374D01*
G01X106004Y1238696D02*
X106241D01*
G01X108136D02*
X108372D01*
G01X108609D02*
X108846D01*
G01X107900D02*
X108136D01*
G01X108372D02*
X108609D01*
G01X107189D02*
X107425D01*
G01X106952D02*
X107189D01*
G01X106714D02*
X106952D01*
G01X107661D02*
X107900D01*
G01X107425D02*
X107661D01*
G01X106477D02*
X106714D01*
G01X110378Y1239030D02*
X110330Y1238757D01*
G01X110425Y1239302D02*
X110378Y1239030D01*
G01X110268Y1238696D02*
X110319D01*
X110330Y1238757D01*
G01X100793Y1238696D02*
X101030D01*
G01X101267D02*
X101503D01*
G01D02*
X101740D01*
G01X101030D02*
X101267D01*
G01X102451D02*
X102687D01*
G01D02*
X102925D01*
G01X101977D02*
X102215D01*
G01D02*
X102451D01*
G01X101740D02*
X101977D01*
G01X103345Y1240462D02*
X103391Y1240734D01*
G01X103489Y1241281D02*
X103535Y1241554D01*
G01X103440Y1241008D02*
X103489Y1241281D01*
G01X103391Y1240734D02*
X103440Y1241008D01*
G01X103296Y1240189D02*
X103345Y1240462D01*
G01X102925Y1238696D02*
X103035D01*
X103058Y1238822D01*
G01D02*
X103105Y1239096D01*
G01X103201Y1239642D02*
X103247Y1239915D01*
G01D02*
X103296Y1240189D01*
G01X103105Y1239096D02*
X103153Y1239369D01*
G01D02*
X103201Y1239642D01*
G01X110268Y1238696D02*
X110330Y1238757D01*
G01X110031Y1238696D02*
X110378Y1239030D01*
G01X109793Y1238696D02*
X110425Y1239302D01*
G01X109557Y1238696D02*
X110474Y1239576D01*
G01X109320Y1238696D02*
X110523Y1239850D01*
G01X109082Y1238696D02*
X110570Y1240123D01*
G01X108846Y1238696D02*
X110618Y1240396D01*
G01X108609Y1238696D02*
X110667Y1240669D01*
G01X108372Y1238696D02*
X110715Y1240943D01*
G01X108136Y1238696D02*
X110763Y1241216D01*
G01X107900Y1238696D02*
X110810Y1241489D01*
G01X107661Y1238696D02*
X110859Y1241763D01*
G01X107425Y1238696D02*
X110907Y1242037D01*
G01X107189Y1238696D02*
X110954Y1242309D01*
G01X106952Y1238696D02*
X111003Y1242582D01*
G01X106714Y1238696D02*
X111052Y1242856D01*
G01X106477Y1238696D02*
X111099Y1243130D01*
G01X106241Y1238696D02*
X111147Y1243403D01*
G01X106004Y1238696D02*
X111196Y1243676D01*
G01X105905Y1238827D02*
X111244Y1243950D01*
G01X105952Y1239101D02*
X111292Y1244223D01*
G01X106001Y1239374D02*
X111339Y1244496D01*
G01X106048Y1239647D02*
X111388Y1244769D01*
G01X106096Y1239921D02*
X111436Y1245043D01*
G01X106145Y1240195D02*
X111483Y1245316D01*
G01X106192Y1240467D02*
X111532Y1245589D01*
G01X106240Y1240740D02*
X111581Y1245863D01*
G01X106288Y1241014D02*
X111628Y1246136D01*
G01X106337Y1241287D02*
X111676Y1246410D01*
G01X102925Y1238696D02*
X103058Y1238822D01*
G01X102687Y1238696D02*
X103105Y1239096D01*
G01X102451Y1238696D02*
X103153Y1239369D01*
G01X102215Y1238696D02*
X103201Y1239642D01*
G01X101977Y1238696D02*
X103247Y1239915D01*
G01X101740Y1238696D02*
X103296Y1240189D01*
G01X101503Y1238696D02*
X103345Y1240462D01*
G01X101267Y1238696D02*
X103391Y1240734D01*
G01X101030Y1238696D02*
X103440Y1241008D01*
G01X100793Y1238696D02*
X103489Y1241281D01*
G01X110523Y1239850D02*
X110474Y1239576D01*
G01X110763Y1241216D02*
X110810Y1241489D01*
G01X110618Y1240396D02*
X110570Y1240123D01*
G01X110474Y1239576D02*
X110425Y1239302D01*
G01X110570Y1240123D02*
X110523Y1239850D01*
G01X110715Y1240943D02*
X110667Y1240669D01*
G01X110763Y1241216D02*
X110715Y1240943D01*
G01X110667Y1240669D02*
X110618Y1240396D01*
G01X106337Y1241287D02*
X106288Y1241014D01*
G01X106383Y1241560D02*
X106337Y1241287D01*
G01X106288Y1241014D02*
X106240Y1240740D01*
G01D02*
X106192Y1240467D01*
G01X110031Y1238696D02*
X110268D01*
G01X109557D02*
X109793D01*
G01D02*
X110031D01*
G01X109320D02*
X109557D01*
G01X109082D02*
X109320D01*
G01X106001Y1239374D02*
X105952Y1239101D01*
G01X106241Y1238696D02*
X106477D01*
G01X108846D02*
X109082D01*
G01X105905Y1238827D02*
X105881Y1238696D01*
X106004D01*
G01X105952Y1239101D02*
X105905Y1238827D01*
G01X106192Y1240467D02*
X106145Y1240195D01*
G01D02*
X106096Y1239921D01*
G01D02*
X106048Y1239647D01*
G01D02*
X106001Y1239374D01*
G01X106004Y1238696D02*
X106241D01*
G01X108136D02*
X108372D01*
G01X108609D02*
X108846D01*
G01X107900D02*
X108136D01*
G01X108372D02*
X108609D01*
G01X107189D02*
X107425D01*
G01X106952D02*
X107189D01*
G01X106714D02*
X106952D01*
G01X107661D02*
X107900D01*
G01X107425D02*
X107661D01*
G01X106477D02*
X106714D01*
G01X110378Y1239030D02*
X110330Y1238757D01*
G01X110425Y1239302D02*
X110378Y1239030D01*
G01X110268Y1238696D02*
X110319D01*
X110330Y1238757D01*
G01X100793Y1238696D02*
X101030D01*
G01X101267D02*
X101503D01*
G01D02*
X101740D01*
G01X101030D02*
X101267D01*
G01X102451D02*
X102687D01*
G01D02*
X102925D01*
G01X101977D02*
X102215D01*
G01D02*
X102451D01*
G01X101740D02*
X101977D01*
G01X103345Y1240462D02*
X103391Y1240734D01*
G01X103489Y1241281D02*
X103535Y1241554D01*
G01X103440Y1241008D02*
X103489Y1241281D01*
G01X103391Y1240734D02*
X103440Y1241008D01*
G01X103296Y1240189D02*
X103345Y1240462D01*
G01X102925Y1238696D02*
X103035D01*
X103058Y1238822D01*
G01D02*
X103105Y1239096D01*
G01X103201Y1239642D02*
X103247Y1239915D01*
G01D02*
X103296Y1240189D01*
G01X103105Y1239096D02*
X103153Y1239369D01*
G01D02*
X103201Y1239642D01*
G01X120451Y1238696D02*
X120527Y1238768D01*
G01X120215Y1238696D02*
X120576Y1239042D01*
G01X119979Y1238696D02*
X120624Y1239315D01*
G01X119741Y1238696D02*
X120671Y1239588D01*
G01X119505Y1238696D02*
X120720Y1239861D01*
G01X119269Y1238696D02*
X120767Y1240134D01*
G01X119031Y1238696D02*
X120815Y1240408D01*
G01X118794Y1238696D02*
X120864Y1240682D01*
G01X118558Y1238696D02*
X120911Y1240954D01*
G01X118320Y1238696D02*
X120959Y1241227D01*
G01X118083Y1238696D02*
X121007Y1241501D01*
G01X117847Y1238696D02*
X121055Y1241774D01*
G01X117610Y1238696D02*
X121102Y1242047D01*
G01X117372Y1238696D02*
X121151Y1242320D01*
G01X117136Y1238696D02*
X121199Y1242593D01*
G01X116899Y1238696D02*
X121246Y1242867D01*
G01X116662Y1238696D02*
X121295Y1243139D01*
G01X116426Y1238696D02*
X121342Y1243413D01*
G01X116188Y1238696D02*
X121390Y1243686D01*
G01X116097Y1238836D02*
X121439Y1243960D01*
G01X116146Y1239109D02*
X121486Y1244232D01*
G01X116194Y1239382D02*
X121534Y1244505D01*
G01X116241Y1239656D02*
X121582Y1244778D01*
G01X116290Y1239929D02*
X121630Y1245052D01*
G01X116338Y1240202D02*
X121677Y1245325D01*
G01X116385Y1240475D02*
X121726Y1245598D01*
G01X116434Y1240749D02*
X121774Y1245872D01*
G01X116483Y1241023D02*
X121821Y1246145D01*
G01X116530Y1241295D02*
X121870Y1246418D01*
G01X117847Y1238696D02*
X118083D01*
G01X118558D02*
X118794D01*
G01X118320D02*
X118558D01*
G01X118083D02*
X118320D01*
G01X118794D02*
X119031D01*
G01D02*
X119269D01*
G01D02*
X119505D01*
G01X116146Y1239109D02*
X116097Y1238836D01*
G01X116194Y1239382D02*
X116146Y1239109D01*
G01X116188Y1238696D02*
X116426D01*
G01D02*
X116662D01*
G01X116241Y1239656D02*
X116194Y1239382D01*
G01X116097Y1238836D02*
X116073Y1238696D01*
X116188D01*
G01X116338Y1240202D02*
X116290Y1239929D01*
G01D02*
X116241Y1239656D01*
G01X117610Y1238696D02*
X117847D01*
G01X116662D02*
X116899D01*
G01X117372D02*
X117610D01*
G01X116899D02*
X117136D01*
G01D02*
X117372D01*
G01X116385Y1240475D02*
X116338Y1240202D01*
G01X116578Y1241569D02*
X116530Y1241295D01*
G01D02*
X116483Y1241023D01*
G01D02*
X116434Y1240749D01*
G01D02*
X116385Y1240475D01*
G01X120720Y1239861D02*
X120671Y1239588D01*
G01X120624Y1239315D02*
X120576Y1239042D01*
G01X120671Y1239588D02*
X120624Y1239315D01*
G01X120576Y1239042D02*
X120527Y1238768D01*
G01X120451Y1238696D02*
X120515D01*
X120527Y1238768D01*
G01X120959Y1241227D02*
X120911Y1240954D01*
G01X121007Y1241501D02*
X120959Y1241227D01*
G01X120815Y1240408D02*
X120767Y1240134D01*
G01D02*
X120720Y1239861D01*
G01X120864Y1240682D02*
X120815Y1240408D01*
G01X120911Y1240954D02*
X120864Y1240682D01*
G01X119741Y1238696D02*
X119979D01*
G01X119505D02*
X119741D01*
G01X119979D02*
X120215D01*
G01D02*
X120451D01*
G01D02*
X120527Y1238768D01*
G01X120215Y1238696D02*
X120576Y1239042D01*
G01X119979Y1238696D02*
X120624Y1239315D01*
G01X119741Y1238696D02*
X120671Y1239588D01*
G01X119505Y1238696D02*
X120720Y1239861D01*
G01X119269Y1238696D02*
X120767Y1240134D01*
G01X119031Y1238696D02*
X120815Y1240408D01*
G01X118794Y1238696D02*
X120864Y1240682D01*
G01X118558Y1238696D02*
X120911Y1240954D01*
G01X118320Y1238696D02*
X120959Y1241227D01*
G01X118083Y1238696D02*
X121007Y1241501D01*
G01X117847Y1238696D02*
X121055Y1241774D01*
G01X117610Y1238696D02*
X121102Y1242047D01*
G01X117372Y1238696D02*
X121151Y1242320D01*
G01X117136Y1238696D02*
X121199Y1242593D01*
G01X116899Y1238696D02*
X121246Y1242867D01*
G01X116662Y1238696D02*
X121295Y1243139D01*
G01X116426Y1238696D02*
X121342Y1243413D01*
G01X116188Y1238696D02*
X121390Y1243686D01*
G01X116097Y1238836D02*
X121439Y1243960D01*
G01X116146Y1239109D02*
X121486Y1244232D01*
G01X116194Y1239382D02*
X121534Y1244505D01*
G01X116241Y1239656D02*
X121582Y1244778D01*
G01X116290Y1239929D02*
X121630Y1245052D01*
G01X116338Y1240202D02*
X121677Y1245325D01*
G01X116385Y1240475D02*
X121726Y1245598D01*
G01X116434Y1240749D02*
X121774Y1245872D01*
G01X116483Y1241023D02*
X121821Y1246145D01*
G01X116530Y1241295D02*
X121870Y1246418D01*
G01X117847Y1238696D02*
X118083D01*
G01X118558D02*
X118794D01*
G01X118320D02*
X118558D01*
G01X118083D02*
X118320D01*
G01X118794D02*
X119031D01*
G01D02*
X119269D01*
G01D02*
X119505D01*
G01X116146Y1239109D02*
X116097Y1238836D01*
G01X116194Y1239382D02*
X116146Y1239109D01*
G01X116188Y1238696D02*
X116426D01*
G01D02*
X116662D01*
G01X116241Y1239656D02*
X116194Y1239382D01*
G01X116097Y1238836D02*
X116073Y1238696D01*
X116188D01*
G01X116338Y1240202D02*
X116290Y1239929D01*
G01D02*
X116241Y1239656D01*
G01X117610Y1238696D02*
X117847D01*
G01X116662D02*
X116899D01*
G01X117372D02*
X117610D01*
G01X116899D02*
X117136D01*
G01D02*
X117372D01*
G01X116385Y1240475D02*
X116338Y1240202D01*
G01X116578Y1241569D02*
X116530Y1241295D01*
G01D02*
X116483Y1241023D01*
G01D02*
X116434Y1240749D01*
G01D02*
X116385Y1240475D01*
G01X120720Y1239861D02*
X120671Y1239588D01*
G01X120624Y1239315D02*
X120576Y1239042D01*
G01X120671Y1239588D02*
X120624Y1239315D01*
G01X120576Y1239042D02*
X120527Y1238768D01*
G01X120451Y1238696D02*
X120515D01*
X120527Y1238768D01*
G01X120959Y1241227D02*
X120911Y1240954D01*
G01X121007Y1241501D02*
X120959Y1241227D01*
G01X120815Y1240408D02*
X120767Y1240134D01*
G01D02*
X120720Y1239861D01*
G01X120864Y1240682D02*
X120815Y1240408D01*
G01X120911Y1240954D02*
X120864Y1240682D01*
G01X119741Y1238696D02*
X119979D01*
G01X119505D02*
X119741D01*
G01X119979D02*
X120215D01*
G01D02*
X120451D01*
G01X106383Y1241560D02*
X111725Y1246683D01*
G01X111772Y1246956D02*
X106432Y1241833D01*
G01X111820Y1247229D02*
X106481Y1242106D01*
G01X111868Y1247503D02*
X106528Y1242380D01*
G01X111917Y1247776D02*
X106576Y1242653D01*
G01X111971Y1248056D02*
X106625Y1242926D01*
G01X112037Y1248346D02*
X106672Y1243200D01*
G01X112102Y1248635D02*
X106720Y1243473D01*
G01X112165Y1248923D02*
X106769Y1243746D01*
G01X112283Y1249263D02*
X106816Y1244019D01*
G01X112403Y1249606D02*
X106863Y1244292D01*
G01X112593Y1250015D02*
X106912Y1244566D01*
G01X112907Y1250544D02*
X106960Y1244839D01*
G01X118202Y1255851D02*
X107007Y1245111D01*
G01X117985Y1255871D02*
X107056Y1245385D01*
G01X117770Y1255890D02*
X107104Y1245659D01*
G01X117554Y1255911D02*
X107151Y1245931D01*
G01X117337Y1255930D02*
X107200Y1246205D01*
G01X111003Y1242582D02*
X111052Y1242856D01*
G01X110954Y1242309D02*
X111003Y1242582D01*
G01X111147Y1243403D02*
X111196Y1243676D01*
G01X111099Y1243130D02*
X111147Y1243403D01*
G01X111052Y1242856D02*
X111099Y1243130D01*
G01X110810Y1241489D02*
X110859Y1241763D01*
G01X110907Y1242037D02*
X110954Y1242309D01*
G01X110859Y1241763D02*
X110907Y1242037D01*
G01X111436Y1245043D02*
X111483Y1245316D01*
G01D02*
X111532Y1245589D01*
G01X111581Y1245863D02*
X111628Y1246136D01*
G01X111532Y1245589D02*
X111581Y1245863D01*
G01X111339Y1244496D02*
X111388Y1244769D01*
G01X111244Y1243950D02*
X111292Y1244223D01*
G01X111196Y1243676D02*
X111244Y1243950D01*
G01X111388Y1244769D02*
X111436Y1245043D01*
G01X111292Y1244223D02*
X111339Y1244496D01*
G01X111628Y1246136D02*
X111676Y1246410D01*
G01X106432Y1241833D02*
X106383Y1241560D01*
G01X106432Y1241833D02*
X106481Y1242106D01*
G01X106863Y1244292D02*
X106816Y1244019D01*
G01X106720Y1243473D02*
X106672Y1243200D01*
G01X106625Y1242926D02*
X106576Y1242653D01*
G01X106816Y1244019D02*
X106769Y1243746D01*
G01D02*
X106720Y1243473D01*
G01X106672Y1243200D02*
X106625Y1242926D01*
G01X106576Y1242653D02*
X106528Y1242380D01*
G01D02*
X106481Y1242106D01*
G01X106912Y1244566D02*
X106863Y1244292D01*
G01X107007Y1245111D02*
X106960Y1244839D01*
G01D02*
X106912Y1244566D01*
G01X107104Y1245659D02*
X107056Y1245385D01*
G01X107200Y1246205D02*
X107151Y1245931D01*
G01D02*
X107104Y1245659D01*
G01X107056Y1245385D02*
X107007Y1245111D01*
G01X107247Y1246478D02*
X107200Y1246205D01*
G01X104110Y1244832D02*
X104159Y1245105D01*
G01X103919Y1243739D02*
X103966Y1244013D01*
G01X103728Y1242647D02*
X103775Y1242920D01*
G01X104015Y1244286D02*
X104063Y1244559D01*
G01D02*
X104110Y1244832D01*
G01X103871Y1243467D02*
X103919Y1243739D01*
G01X103966Y1244013D02*
X104015Y1244286D01*
G01X104206Y1245379D02*
X104254Y1245652D01*
G01X104159Y1245105D02*
X104206Y1245379D01*
G01X103535Y1241554D02*
X103584Y1241827D01*
G01X103679Y1242374D02*
X103728Y1242647D01*
G01X103775Y1242920D02*
X103823Y1243194D01*
G01D02*
X103871Y1243467D01*
G01X103631Y1242100D02*
X103679Y1242374D01*
G01X103584Y1241827D02*
X103631Y1242100D01*
G01X104303Y1245925D02*
X104350Y1246198D01*
G01D02*
X104398Y1246471D01*
G01X104254Y1245652D02*
X104303Y1245925D01*
G01X106383Y1241560D02*
X111725Y1246683D01*
G01X111772Y1246956D02*
X106432Y1241833D01*
G01X111820Y1247229D02*
X106481Y1242106D01*
G01X111868Y1247503D02*
X106528Y1242380D01*
G01X111917Y1247776D02*
X106576Y1242653D01*
G01X111971Y1248056D02*
X106625Y1242926D01*
G01X112037Y1248346D02*
X106672Y1243200D01*
G01X112102Y1248635D02*
X106720Y1243473D01*
G01X112165Y1248923D02*
X106769Y1243746D01*
G01X112283Y1249263D02*
X106816Y1244019D01*
G01X112403Y1249606D02*
X106863Y1244292D01*
G01X112593Y1250015D02*
X106912Y1244566D01*
G01X112907Y1250544D02*
X106960Y1244839D01*
G01X118202Y1255851D02*
X107007Y1245111D01*
G01X117985Y1255871D02*
X107056Y1245385D01*
G01X117770Y1255890D02*
X107104Y1245659D01*
G01X117554Y1255911D02*
X107151Y1245931D01*
G01X117337Y1255930D02*
X107200Y1246205D01*
G01X111003Y1242582D02*
X111052Y1242856D01*
G01X110954Y1242309D02*
X111003Y1242582D01*
G01X111147Y1243403D02*
X111196Y1243676D01*
G01X111099Y1243130D02*
X111147Y1243403D01*
G01X111052Y1242856D02*
X111099Y1243130D01*
G01X110810Y1241489D02*
X110859Y1241763D01*
G01X110907Y1242037D02*
X110954Y1242309D01*
G01X110859Y1241763D02*
X110907Y1242037D01*
G01X111436Y1245043D02*
X111483Y1245316D01*
G01D02*
X111532Y1245589D01*
G01X111581Y1245863D02*
X111628Y1246136D01*
G01X111532Y1245589D02*
X111581Y1245863D01*
G01X111339Y1244496D02*
X111388Y1244769D01*
G01X111244Y1243950D02*
X111292Y1244223D01*
G01X111196Y1243676D02*
X111244Y1243950D01*
G01X111388Y1244769D02*
X111436Y1245043D01*
G01X111292Y1244223D02*
X111339Y1244496D01*
G01X111628Y1246136D02*
X111676Y1246410D01*
G01X106432Y1241833D02*
X106383Y1241560D01*
G01X106432Y1241833D02*
X106481Y1242106D01*
G01X106863Y1244292D02*
X106816Y1244019D01*
G01X106720Y1243473D02*
X106672Y1243200D01*
G01X106625Y1242926D02*
X106576Y1242653D01*
G01X106816Y1244019D02*
X106769Y1243746D01*
G01D02*
X106720Y1243473D01*
G01X106672Y1243200D02*
X106625Y1242926D01*
G01X106576Y1242653D02*
X106528Y1242380D01*
G01D02*
X106481Y1242106D01*
G01X106912Y1244566D02*
X106863Y1244292D01*
G01X107007Y1245111D02*
X106960Y1244839D01*
G01D02*
X106912Y1244566D01*
G01X107104Y1245659D02*
X107056Y1245385D01*
G01X107200Y1246205D02*
X107151Y1245931D01*
G01D02*
X107104Y1245659D01*
G01X107056Y1245385D02*
X107007Y1245111D01*
G01X107247Y1246478D02*
X107200Y1246205D01*
G01X104110Y1244832D02*
X104159Y1245105D01*
G01X103919Y1243739D02*
X103966Y1244013D01*
G01X103728Y1242647D02*
X103775Y1242920D01*
G01X104015Y1244286D02*
X104063Y1244559D01*
G01D02*
X104110Y1244832D01*
G01X103871Y1243467D02*
X103919Y1243739D01*
G01X103966Y1244013D02*
X104015Y1244286D01*
G01X104206Y1245379D02*
X104254Y1245652D01*
G01X104159Y1245105D02*
X104206Y1245379D01*
G01X103535Y1241554D02*
X103584Y1241827D01*
G01X103679Y1242374D02*
X103728Y1242647D01*
G01X103775Y1242920D02*
X103823Y1243194D01*
G01D02*
X103871Y1243467D01*
G01X103631Y1242100D02*
X103679Y1242374D01*
G01X103584Y1241827D02*
X103631Y1242100D01*
G01X104303Y1245925D02*
X104350Y1246198D01*
G01D02*
X104398Y1246471D01*
G01X104254Y1245652D02*
X104303Y1245925D01*
G01X118634Y1255811D02*
X114178Y1251536D01*
G01X118418Y1255831D02*
X113716Y1251320D01*
G01X117083Y1255913D02*
X107247Y1246478D01*
G01X116822Y1255890D02*
X107295Y1246751D01*
G01X116559Y1255865D02*
X107344Y1247024D01*
G01X116298Y1255841D02*
X107391Y1247297D01*
G01X116035Y1255817D02*
X107439Y1247571D01*
G01X115704Y1255727D02*
X107487Y1247844D01*
G01X115372Y1255635D02*
X107535Y1248117D01*
G01X115039Y1255542D02*
X107582Y1248390D01*
G01X114638Y1255385D02*
X107631Y1248664D01*
G01X114167Y1255162D02*
X107679Y1248937D01*
G01X113518Y1254765D02*
X107726Y1249210D01*
G01X113111Y1254602D02*
X107775Y1249483D01*
G01X113160Y1254876D02*
X107824Y1249757D01*
G01X113207Y1255149D02*
X107870Y1250030D01*
G01X113255Y1255422D02*
X107919Y1250303D01*
G01X113184Y1255581D02*
X107968Y1250576D01*
G01X112947Y1255581D02*
X108014Y1250849D01*
G01X112709Y1255581D02*
X108062Y1251123D01*
G01X112473Y1255581D02*
X108111Y1251396D01*
G01X112237Y1255581D02*
X108159Y1251669D01*
G01X112000Y1255581D02*
X108206Y1251942D01*
G01X111763Y1255581D02*
X108255Y1252216D01*
G01X111527Y1255581D02*
X108303Y1252489D01*
G01X111289Y1255581D02*
X108350Y1252762D01*
G01X111052Y1255581D02*
X108399Y1253035D01*
G01X110816Y1255581D02*
X108446Y1253308D01*
G01X110578Y1255581D02*
X108494Y1253582D01*
G01X110341Y1255581D02*
X108543Y1253854D01*
G01X110105Y1255581D02*
X108590Y1254128D01*
G01X109868Y1255581D02*
X108638Y1254402D01*
G01X109630Y1255581D02*
X108686Y1254674D01*
G01X109394Y1255581D02*
X108734Y1254948D01*
G01X109157Y1255581D02*
X108781Y1255221D01*
G01X108920Y1255581D02*
X108830Y1255494D01*
G01X111725Y1246683D02*
X111676Y1246410D01*
G01X113255Y1255422D02*
X113283Y1255581D01*
X113184D01*
G01X113207Y1255149D02*
X113255Y1255422D01*
G01X113111Y1254602D02*
X113160Y1254876D01*
G01D02*
X113207Y1255149D01*
G01X112709Y1255581D02*
X112473D01*
G01D02*
X112237D01*
G01X113184D02*
X112947D01*
G01D02*
X112709D01*
G01X112237D02*
X112000D01*
G01X111772Y1246956D02*
X111725Y1246683D01*
G01X111820Y1247229D02*
X111772Y1246956D01*
G01X110578Y1255581D02*
X110341D01*
G01X109394D02*
X109157D01*
G01X109868D02*
X109630D01*
G01X112000D02*
X111763D01*
G01X110105D02*
X109868D01*
G01X110341D02*
X110105D01*
G01X109630D02*
X109394D01*
G01X111289D02*
X111052D01*
G01X111527D02*
X111289D01*
G01X110816D02*
X110578D01*
G01X111763D02*
X111527D01*
G01X109157D02*
X108920D01*
G01X111052D02*
X110816D01*
G01X111868Y1247503D02*
X111820Y1247229D01*
G01X107775Y1249483D02*
X107726Y1249210D01*
G01X111917Y1247776D02*
X111868Y1247503D01*
G01X107726Y1249210D02*
X107679Y1248937D01*
G01X108255Y1252216D02*
X108303Y1252489D01*
G01D02*
X108350Y1252762D01*
G01X108399Y1253035D02*
X108446Y1253308D01*
G01X108159Y1251669D02*
X108111Y1251396D01*
G01D02*
X108062Y1251123D01*
G01X108206Y1251942D02*
X108255Y1252216D01*
G01X108159Y1251669D02*
X108206Y1251942D01*
G01X108446Y1253308D02*
X108494Y1253582D01*
G01X108350Y1252762D02*
X108399Y1253035D01*
G01X108920Y1255581D02*
X108845D01*
X108830Y1255494D01*
G01X108781Y1255221D02*
X108830Y1255494D01*
G01X108543Y1253854D02*
X108590Y1254128D01*
G01X108494Y1253582D02*
X108543Y1253854D01*
G01X108734Y1254948D02*
X108781Y1255221D01*
G01X108590Y1254128D02*
X108638Y1254402D01*
G01D02*
X108686Y1254674D01*
G01D02*
X108734Y1254948D01*
G01X108062Y1251123D02*
X108014Y1250849D01*
G01X107439Y1247571D02*
X107391Y1247297D01*
G01X107487Y1247844D02*
X107439Y1247571D01*
G01X107391Y1247297D02*
X107344Y1247024D01*
G01X108014Y1250849D02*
X107968Y1250576D01*
G01X107344Y1247024D02*
X107295Y1246751D01*
G01D02*
X107247Y1246478D01*
G01X107824Y1249757D02*
X107775Y1249483D01*
G01X107870Y1250030D02*
X107824Y1249757D01*
G01X107919Y1250303D02*
X107870Y1250030D01*
G01X107968Y1250576D02*
X107919Y1250303D01*
G01X107679Y1248937D02*
X107631Y1248664D01*
G01X107582Y1248390D02*
X107535Y1248117D01*
G01X107631Y1248664D02*
X107582Y1248390D01*
G01X107535Y1248117D02*
X107487Y1247844D01*
G01X104782Y1248657D02*
X104734Y1248383D01*
G01X104925Y1249476D02*
X104878Y1249203D01*
G01X104973Y1249749D02*
X104925Y1249476D01*
G01X104829Y1248930D02*
X104782Y1248657D01*
G01X104878Y1249203D02*
X104829Y1248930D01*
G01X104590Y1247564D02*
X104638Y1247838D01*
G01X104541Y1247290D02*
X104590Y1247564D01*
G01X104638Y1247838D02*
X104685Y1248110D01*
G01X104734Y1248383D02*
X104685Y1248110D01*
G01X104446Y1246744D02*
X104494Y1247018D01*
G01X104398Y1246471D02*
X104446Y1246744D01*
G01X104494Y1247018D02*
X104541Y1247290D01*
G01X118634Y1255811D02*
X114178Y1251536D01*
G01X118418Y1255831D02*
X113716Y1251320D01*
G01X117083Y1255913D02*
X107247Y1246478D01*
G01X116822Y1255890D02*
X107295Y1246751D01*
G01X116559Y1255865D02*
X107344Y1247024D01*
G01X116298Y1255841D02*
X107391Y1247297D01*
G01X116035Y1255817D02*
X107439Y1247571D01*
G01X115704Y1255727D02*
X107487Y1247844D01*
G01X115372Y1255635D02*
X107535Y1248117D01*
G01X115039Y1255542D02*
X107582Y1248390D01*
G01X114638Y1255385D02*
X107631Y1248664D01*
G01X114167Y1255162D02*
X107679Y1248937D01*
G01X113518Y1254765D02*
X107726Y1249210D01*
G01X113111Y1254602D02*
X107775Y1249483D01*
G01X113160Y1254876D02*
X107824Y1249757D01*
G01X113207Y1255149D02*
X107870Y1250030D01*
G01X113255Y1255422D02*
X107919Y1250303D01*
G01X113184Y1255581D02*
X107968Y1250576D01*
G01X112947Y1255581D02*
X108014Y1250849D01*
G01X112709Y1255581D02*
X108062Y1251123D01*
G01X112473Y1255581D02*
X108111Y1251396D01*
G01X112237Y1255581D02*
X108159Y1251669D01*
G01X112000Y1255581D02*
X108206Y1251942D01*
G01X111763Y1255581D02*
X108255Y1252216D01*
G01X111527Y1255581D02*
X108303Y1252489D01*
G01X111289Y1255581D02*
X108350Y1252762D01*
G01X111052Y1255581D02*
X108399Y1253035D01*
G01X110816Y1255581D02*
X108446Y1253308D01*
G01X110578Y1255581D02*
X108494Y1253582D01*
G01X110341Y1255581D02*
X108543Y1253854D01*
G01X110105Y1255581D02*
X108590Y1254128D01*
G01X109868Y1255581D02*
X108638Y1254402D01*
G01X109630Y1255581D02*
X108686Y1254674D01*
G01X109394Y1255581D02*
X108734Y1254948D01*
G01X109157Y1255581D02*
X108781Y1255221D01*
G01X108920Y1255581D02*
X108830Y1255494D01*
G01X111725Y1246683D02*
X111676Y1246410D01*
G01X113255Y1255422D02*
X113283Y1255581D01*
X113184D01*
G01X113207Y1255149D02*
X113255Y1255422D01*
G01X113111Y1254602D02*
X113160Y1254876D01*
G01D02*
X113207Y1255149D01*
G01X112709Y1255581D02*
X112473D01*
G01D02*
X112237D01*
G01X113184D02*
X112947D01*
G01D02*
X112709D01*
G01X112237D02*
X112000D01*
G01X111772Y1246956D02*
X111725Y1246683D01*
G01X111820Y1247229D02*
X111772Y1246956D01*
G01X110578Y1255581D02*
X110341D01*
G01X109394D02*
X109157D01*
G01X109868D02*
X109630D01*
G01X112000D02*
X111763D01*
G01X110105D02*
X109868D01*
G01X110341D02*
X110105D01*
G01X109630D02*
X109394D01*
G01X111289D02*
X111052D01*
G01X111527D02*
X111289D01*
G01X110816D02*
X110578D01*
G01X111763D02*
X111527D01*
G01X109157D02*
X108920D01*
G01X111052D02*
X110816D01*
G01X111868Y1247503D02*
X111820Y1247229D01*
G01X107775Y1249483D02*
X107726Y1249210D01*
G01X111917Y1247776D02*
X111868Y1247503D01*
G01X107726Y1249210D02*
X107679Y1248937D01*
G01X108255Y1252216D02*
X108303Y1252489D01*
G01D02*
X108350Y1252762D01*
G01X108399Y1253035D02*
X108446Y1253308D01*
G01X108159Y1251669D02*
X108111Y1251396D01*
G01D02*
X108062Y1251123D01*
G01X108206Y1251942D02*
X108255Y1252216D01*
G01X108159Y1251669D02*
X108206Y1251942D01*
G01X108446Y1253308D02*
X108494Y1253582D01*
G01X108350Y1252762D02*
X108399Y1253035D01*
G01X108920Y1255581D02*
X108845D01*
X108830Y1255494D01*
G01X108781Y1255221D02*
X108830Y1255494D01*
G01X108543Y1253854D02*
X108590Y1254128D01*
G01X108494Y1253582D02*
X108543Y1253854D01*
G01X108734Y1254948D02*
X108781Y1255221D01*
G01X108590Y1254128D02*
X108638Y1254402D01*
G01D02*
X108686Y1254674D01*
G01D02*
X108734Y1254948D01*
G01X108062Y1251123D02*
X108014Y1250849D01*
G01X107439Y1247571D02*
X107391Y1247297D01*
G01X107487Y1247844D02*
X107439Y1247571D01*
G01X107391Y1247297D02*
X107344Y1247024D01*
G01X108014Y1250849D02*
X107968Y1250576D01*
G01X107344Y1247024D02*
X107295Y1246751D01*
G01D02*
X107247Y1246478D01*
G01X107824Y1249757D02*
X107775Y1249483D01*
G01X107870Y1250030D02*
X107824Y1249757D01*
G01X107919Y1250303D02*
X107870Y1250030D01*
G01X107968Y1250576D02*
X107919Y1250303D01*
G01X107679Y1248937D02*
X107631Y1248664D01*
G01X107582Y1248390D02*
X107535Y1248117D01*
G01X107631Y1248664D02*
X107582Y1248390D01*
G01X107535Y1248117D02*
X107487Y1247844D01*
G01X104782Y1248657D02*
X104734Y1248383D01*
G01X104925Y1249476D02*
X104878Y1249203D01*
G01X104973Y1249749D02*
X104925Y1249476D01*
G01X104829Y1248930D02*
X104782Y1248657D01*
G01X104878Y1249203D02*
X104829Y1248930D01*
G01X104590Y1247564D02*
X104638Y1247838D01*
G01X104541Y1247290D02*
X104590Y1247564D01*
G01X104638Y1247838D02*
X104685Y1248110D01*
G01X104734Y1248383D02*
X104685Y1248110D01*
G01X104446Y1246744D02*
X104494Y1247018D01*
G01X104398Y1246471D02*
X104446Y1246744D01*
G01X104494Y1247018D02*
X104541Y1247290D01*
G01X116578Y1241569D02*
X121917Y1246691D01*
G01X116626Y1241842D02*
X121965Y1246964D01*
G01X116674Y1242116D02*
X122014Y1247238D01*
G01X116721Y1242389D02*
X122061Y1247511D01*
G01X116770Y1242662D02*
X122109Y1247783D01*
G01X116819Y1242935D02*
X122158Y1248057D01*
G01X116866Y1243208D02*
X122198Y1248324D01*
G01X116914Y1243482D02*
X122229Y1248581D01*
G01X116963Y1243755D02*
X122261Y1248837D01*
G01X117010Y1244028D02*
X122292Y1249095D01*
G01X117058Y1244302D02*
X122323Y1249353D01*
G01X117107Y1244575D02*
X122356Y1249610D01*
G01X117154Y1244848D02*
X122385Y1249867D01*
G01X117201Y1245122D02*
X122391Y1250099D01*
G01X122388Y1250324D02*
X117250Y1245395D01*
G01X117299Y1245668D02*
X122387Y1250550D01*
G01X117347Y1245941D02*
X122385Y1250775D01*
G01X117394Y1246215D02*
X122383Y1251001D01*
G01X116721Y1242389D02*
X116674Y1242116D01*
G01X117154Y1244848D02*
X117107Y1244575D01*
G01D02*
X117058Y1244302D01*
G01X116963Y1243755D02*
X116914Y1243482D01*
G01X117010Y1244028D02*
X116963Y1243755D01*
G01X117058Y1244302D02*
X117010Y1244028D01*
G01X116626Y1241842D02*
X116578Y1241569D01*
G01X116914Y1243482D02*
X116866Y1243208D01*
G01D02*
X116819Y1242935D01*
G01D02*
X116770Y1242662D01*
G01X116674Y1242116D02*
X116626Y1241842D01*
G01X116770Y1242662D02*
X116721Y1242389D01*
G01X117201Y1245122D02*
X117154Y1244848D01*
G01X117443Y1246488D02*
X117394Y1246215D01*
G01X117299Y1245668D02*
X117250Y1245395D01*
G01X117394Y1246215D02*
X117347Y1245941D01*
G01X121246Y1242867D02*
X121199Y1242593D01*
G01X121295Y1243139D02*
X121246Y1242867D01*
G01X121390Y1243686D02*
X121342Y1243413D01*
G01X121439Y1243960D02*
X121390Y1243686D01*
G01X121342Y1243413D02*
X121295Y1243139D01*
G01X121055Y1241774D02*
X121007Y1241501D01*
G01X121102Y1242047D02*
X121055Y1241774D01*
G01X121151Y1242320D02*
X121102Y1242047D01*
G01X121199Y1242593D02*
X121151Y1242320D01*
G01X121774Y1245872D02*
X121726Y1245598D01*
G01X121870Y1246418D02*
X121821Y1246145D01*
G01X121486Y1244232D02*
X121439Y1243960D01*
G01X121630Y1245052D02*
X121582Y1244778D01*
G01X121677Y1245325D02*
X121630Y1245052D01*
G01X121582Y1244778D02*
X121534Y1244505D01*
G01D02*
X121486Y1244232D01*
G01X121821Y1246145D02*
X121774Y1245872D01*
G01X121726Y1245598D02*
X121677Y1245325D01*
G01X117201Y1245122D02*
X117250Y1245395D01*
G01X117347Y1245941D02*
X117299Y1245668D01*
G01X116578Y1241569D02*
X121917Y1246691D01*
G01X116626Y1241842D02*
X121965Y1246964D01*
G01X116674Y1242116D02*
X122014Y1247238D01*
G01X116721Y1242389D02*
X122061Y1247511D01*
G01X116770Y1242662D02*
X122109Y1247783D01*
G01X116819Y1242935D02*
X122158Y1248057D01*
G01X116866Y1243208D02*
X122198Y1248324D01*
G01X116914Y1243482D02*
X122229Y1248581D01*
G01X116963Y1243755D02*
X122261Y1248837D01*
G01X117010Y1244028D02*
X122292Y1249095D01*
G01X117058Y1244302D02*
X122323Y1249353D01*
G01X117107Y1244575D02*
X122356Y1249610D01*
G01X117154Y1244848D02*
X122385Y1249867D01*
G01X117201Y1245122D02*
X122391Y1250099D01*
G01X122388Y1250324D02*
X117250Y1245395D01*
G01X117299Y1245668D02*
X122387Y1250550D01*
G01X117347Y1245941D02*
X122385Y1250775D01*
G01X117394Y1246215D02*
X122383Y1251001D01*
G01X116721Y1242389D02*
X116674Y1242116D01*
G01X117154Y1244848D02*
X117107Y1244575D01*
G01D02*
X117058Y1244302D01*
G01X116963Y1243755D02*
X116914Y1243482D01*
G01X117010Y1244028D02*
X116963Y1243755D01*
G01X117058Y1244302D02*
X117010Y1244028D01*
G01X116626Y1241842D02*
X116578Y1241569D01*
G01X116914Y1243482D02*
X116866Y1243208D01*
G01D02*
X116819Y1242935D01*
G01D02*
X116770Y1242662D01*
G01X116674Y1242116D02*
X116626Y1241842D01*
G01X116770Y1242662D02*
X116721Y1242389D01*
G01X117201Y1245122D02*
X117154Y1244848D01*
G01X117443Y1246488D02*
X117394Y1246215D01*
G01X117299Y1245668D02*
X117250Y1245395D01*
G01X117394Y1246215D02*
X117347Y1245941D01*
G01X121246Y1242867D02*
X121199Y1242593D01*
G01X121295Y1243139D02*
X121246Y1242867D01*
G01X121390Y1243686D02*
X121342Y1243413D01*
G01X121439Y1243960D02*
X121390Y1243686D01*
G01X121342Y1243413D02*
X121295Y1243139D01*
G01X121055Y1241774D02*
X121007Y1241501D01*
G01X121102Y1242047D02*
X121055Y1241774D01*
G01X121151Y1242320D02*
X121102Y1242047D01*
G01X121199Y1242593D02*
X121151Y1242320D01*
G01X121774Y1245872D02*
X121726Y1245598D01*
G01X121870Y1246418D02*
X121821Y1246145D01*
G01X121486Y1244232D02*
X121439Y1243960D01*
G01X121630Y1245052D02*
X121582Y1244778D01*
G01X121677Y1245325D02*
X121630Y1245052D01*
G01X121582Y1244778D02*
X121534Y1244505D01*
G01D02*
X121486Y1244232D01*
G01X121821Y1246145D02*
X121774Y1245872D01*
G01X121726Y1245598D02*
X121677Y1245325D01*
G01X117201Y1245122D02*
X117250Y1245395D01*
G01X117347Y1245941D02*
X117299Y1245668D01*
G01X117443Y1246488D02*
X122383Y1251226D01*
G01X117490Y1246761D02*
X122377Y1251448D01*
G01X117538Y1247034D02*
X122342Y1251642D01*
G01X117587Y1247308D02*
X122307Y1251836D01*
G01X122271Y1252030D02*
X117636Y1247581D01*
G01X122238Y1252223D02*
X117682Y1247853D01*
G01X122202Y1252417D02*
X117714Y1248112D01*
G01X122168Y1252611D02*
X117749Y1248372D01*
G01X122122Y1252796D02*
X117782Y1248632D01*
G01X122054Y1252957D02*
X117813Y1248888D01*
G01X121987Y1253119D02*
X117815Y1249117D01*
G01X121917Y1253280D02*
X117817Y1249347D01*
G01X121848Y1253442D02*
X117820Y1249576D01*
G01X121780Y1253603D02*
X117809Y1249793D01*
G01X121713Y1253764D02*
X117777Y1249989D01*
G01X121629Y1253913D02*
X117744Y1250185D01*
G01X121525Y1254041D02*
X117711Y1250381D01*
G01X121422Y1254169D02*
X117645Y1250545D01*
G01X121319Y1254297D02*
X117576Y1250705D01*
G01X121216Y1254426D02*
X117505Y1250865D01*
G01X121113Y1254554D02*
X117410Y1251003D01*
G01X121010Y1254682D02*
X117302Y1251125D01*
G01X120891Y1254794D02*
X117193Y1251248D01*
G01X120751Y1254888D02*
X117066Y1251353D01*
G01X120611Y1254981D02*
X116917Y1251437D01*
G01X120473Y1255076D02*
X116770Y1251523D01*
G01X120335Y1255169D02*
X116603Y1251590D01*
G01X120196Y1255264D02*
X116418Y1251639D01*
G01X120057Y1255358D02*
X116230Y1251688D01*
G01X119895Y1255430D02*
X116027Y1251719D01*
G01X119720Y1255489D02*
X115806Y1251734D01*
G01X119543Y1255547D02*
X115585Y1251749D01*
G01X119366Y1255605D02*
X115342Y1251744D01*
G01X119190Y1255663D02*
X115087Y1251726D01*
G01X119014Y1255721D02*
X114831Y1251707D01*
G01X118837Y1255779D02*
X114515Y1251632D01*
G01X117636Y1247581D02*
X117587Y1247308D01*
G01X122061Y1247511D02*
X122014Y1247238D01*
G01X122109Y1247783D02*
X122061Y1247511D01*
G01X117587Y1247308D02*
X117538Y1247034D01*
G01X121965Y1246964D02*
X121917Y1246691D01*
G01D02*
X121870Y1246418D01*
G01X122014Y1247238D02*
X121965Y1246964D01*
G01X117490Y1246761D02*
X117443Y1246488D01*
G01X122158Y1248057D02*
X122109Y1247783D01*
G01X117538Y1247034D02*
X117490Y1246761D01*
G01X117443Y1246488D02*
X122383Y1251226D01*
G01X117490Y1246761D02*
X122377Y1251448D01*
G01X117538Y1247034D02*
X122342Y1251642D01*
G01X117587Y1247308D02*
X122307Y1251836D01*
G01X122271Y1252030D02*
X117636Y1247581D01*
G01X122238Y1252223D02*
X117682Y1247853D01*
G01X122202Y1252417D02*
X117714Y1248112D01*
G01X122168Y1252611D02*
X117749Y1248372D01*
G01X122122Y1252796D02*
X117782Y1248632D01*
G01X122054Y1252957D02*
X117813Y1248888D01*
G01X121987Y1253119D02*
X117815Y1249117D01*
G01X121917Y1253280D02*
X117817Y1249347D01*
G01X121848Y1253442D02*
X117820Y1249576D01*
G01X121780Y1253603D02*
X117809Y1249793D01*
G01X121713Y1253764D02*
X117777Y1249989D01*
G01X121629Y1253913D02*
X117744Y1250185D01*
G01X121525Y1254041D02*
X117711Y1250381D01*
G01X121422Y1254169D02*
X117645Y1250545D01*
G01X121319Y1254297D02*
X117576Y1250705D01*
G01X121216Y1254426D02*
X117505Y1250865D01*
G01X121113Y1254554D02*
X117410Y1251003D01*
G01X121010Y1254682D02*
X117302Y1251125D01*
G01X120891Y1254794D02*
X117193Y1251248D01*
G01X120751Y1254888D02*
X117066Y1251353D01*
G01X120611Y1254981D02*
X116917Y1251437D01*
G01X120473Y1255076D02*
X116770Y1251523D01*
G01X120335Y1255169D02*
X116603Y1251590D01*
G01X120196Y1255264D02*
X116418Y1251639D01*
G01X120057Y1255358D02*
X116230Y1251688D01*
G01X119895Y1255430D02*
X116027Y1251719D01*
G01X119720Y1255489D02*
X115806Y1251734D01*
G01X119543Y1255547D02*
X115585Y1251749D01*
G01X119366Y1255605D02*
X115342Y1251744D01*
G01X119190Y1255663D02*
X115087Y1251726D01*
G01X119014Y1255721D02*
X114831Y1251707D01*
G01X118837Y1255779D02*
X114515Y1251632D01*
G01X117636Y1247581D02*
X117587Y1247308D01*
G01X122061Y1247511D02*
X122014Y1247238D01*
G01X122109Y1247783D02*
X122061Y1247511D01*
G01X117587Y1247308D02*
X117538Y1247034D01*
G01X121965Y1246964D02*
X121917Y1246691D01*
G01D02*
X121870Y1246418D01*
G01X122014Y1247238D02*
X121965Y1246964D01*
G01X117490Y1246761D02*
X117443Y1246488D01*
G01X122158Y1248057D02*
X122109Y1247783D01*
G01X117538Y1247034D02*
X117490Y1246761D01*
G01X146980Y1238696D02*
X151335Y1242873D01*
G01X146744Y1238696D02*
X151383Y1243146D01*
G01X146507Y1238696D02*
X151430Y1243420D01*
G01X146269Y1238696D02*
X151479Y1243693D01*
G01X146192Y1238848D02*
X151526Y1243966D01*
G01X146239Y1239122D02*
X151574Y1244239D01*
G01X146288Y1239395D02*
X151623Y1244513D01*
G01X151670Y1244786D02*
X146336Y1239669D01*
G01X145952Y1239528D02*
X151718Y1245058D01*
G01X145278Y1239108D02*
X151765Y1245331D01*
G01X144804Y1238881D02*
X151814Y1245605D01*
G01X144399Y1238719D02*
X151861Y1245878D01*
G01X144062Y1238624D02*
X151909Y1246151D01*
G01X143726Y1238528D02*
X151958Y1246424D01*
G01X143407Y1238450D02*
X152005Y1246698D01*
G01X143143Y1238423D02*
X152053Y1246971D01*
G01X142880Y1238399D02*
X152100Y1247244D01*
G01X142617Y1238372D02*
X152149Y1247516D01*
G01X142352Y1238347D02*
X152196Y1247790D01*
G01X142119Y1238350D02*
X152244Y1248063D01*
G01X141891Y1238358D02*
X152293Y1248336D01*
G01X152340Y1248609D02*
X141668Y1238372D01*
G01X141457Y1238396D02*
X146094Y1242845D01*
G01X141247Y1238422D02*
X145522Y1242523D01*
G01X141045Y1238454D02*
X145141Y1242384D01*
G01X140849Y1238494D02*
X144760Y1242245D01*
G01X140654Y1238534D02*
X144477Y1242203D01*
G01X140468Y1238585D02*
X144205Y1242169D01*
G01X140288Y1238638D02*
X143934Y1242136D01*
G01X140107Y1238692D02*
X143665Y1242105D01*
G01X139938Y1238757D02*
X143445Y1242121D01*
G01X139771Y1238825D02*
X143226Y1242138D01*
G01X139604Y1238892D02*
X143009Y1242157D01*
G01X139448Y1238969D02*
X142823Y1242206D01*
G01X139295Y1239050D02*
X142637Y1242254D01*
G01X139143Y1239131D02*
X142459Y1242313D01*
G01X138998Y1239219D02*
X142307Y1242393D01*
G01X138861Y1239313D02*
X142154Y1242473D01*
G01X138721Y1239408D02*
X142021Y1242574D01*
G01X138588Y1239508D02*
X141902Y1242686D01*
G01X138465Y1239615D02*
X141785Y1242802D01*
G01X138340Y1239723D02*
X141698Y1242945D01*
G01X138218Y1239834D02*
X141613Y1243090D01*
G01X138108Y1239956D02*
X141553Y1243261D01*
G01X138000Y1240078D02*
X141502Y1243438D01*
G01X137890Y1240201D02*
X141473Y1243637D01*
G01X137795Y1240336D02*
X141457Y1243850D01*
G01X137700Y1240473D02*
X141469Y1244089D01*
G01X137606Y1240610D02*
X141495Y1244340D01*
G01X137523Y1240758D02*
X141613Y1244681D01*
G01X137446Y1240911D02*
X141739Y1245029D01*
G01X137369Y1241064D02*
X142401Y1245892D01*
G01X137298Y1241224D02*
X146279Y1249838D01*
G01X132993Y1239139D02*
X133486Y1239611D01*
G01X132509Y1238901D02*
X133590Y1239939D01*
G01X132123Y1238758D02*
X133695Y1240266D01*
G01X131751Y1238628D02*
X133798Y1240593D01*
G01X131443Y1238559D02*
X133902Y1240919D01*
G01X131134Y1238491D02*
X134007Y1241246D01*
G01X130826Y1238423D02*
X134111Y1241574D01*
G01X130568Y1238402D02*
X134214Y1241900D01*
G01X130310Y1238383D02*
X134318Y1242227D01*
G01X130053Y1238364D02*
X134422Y1242554D01*
G01X129795Y1238342D02*
X134526Y1242882D01*
G01X129581Y1238364D02*
X134630Y1243208D01*
G01X129366Y1238385D02*
X134734Y1243535D01*
G01X129151Y1238407D02*
X134838Y1243862D01*
G01X128937Y1238429D02*
X133985Y1243271D01*
G01X128743Y1238469D02*
X133393Y1242930D01*
G01X128568Y1238529D02*
X132980Y1242761D01*
G01X128393Y1238587D02*
X132626Y1242649D01*
G01X128216Y1238647D02*
X132356Y1242617D01*
G01X128043Y1238705D02*
X132090Y1242589D01*
G01X127894Y1238789D02*
X131866Y1242601D01*
G01X127752Y1238882D02*
X131656Y1242627D01*
G01X127610Y1238974D02*
X131462Y1242669D01*
G01X127470Y1239066D02*
X131298Y1242738D01*
G01X127329Y1239158D02*
X131146Y1242820D01*
G01X127214Y1239276D02*
X131029Y1242934D01*
G01X127104Y1239398D02*
X130929Y1243066D01*
G01X126994Y1239519D02*
X130852Y1243219D01*
G01X126884Y1239641D02*
X130801Y1243398D01*
G01X126775Y1239763D02*
X130764Y1243589D01*
G01X126692Y1239911D02*
X130757Y1243809D01*
G01X126613Y1240062D02*
X130755Y1244036D01*
G01X126533Y1240212D02*
X130784Y1244289D01*
G01X126453Y1240363D02*
X130816Y1244548D01*
G01X126373Y1240514D02*
X130860Y1244818D01*
G01X126324Y1240694D02*
X130909Y1245091D01*
G01X126275Y1240874D02*
X130956Y1245364D01*
G01X126227Y1241055D02*
X131005Y1245638D01*
G01X126178Y1241236D02*
X131052Y1245912D01*
G01X146269Y1238696D02*
X146507D01*
G01X146288Y1239395D02*
X146239Y1239122D01*
G01X146192Y1238848D02*
X146165Y1238696D01*
X146269D01*
G01X146239Y1239122D02*
X146192Y1238848D01*
G01X146744Y1238696D02*
X146980D01*
G01D02*
X147216D01*
G01X146507D02*
X146744D01*
G01X146336Y1239669D02*
X146288Y1239395D01*
G01X134111Y1241574D02*
X134007Y1241246D01*
G01D02*
X133902Y1240919D01*
G01D02*
X133798Y1240593D01*
G01D02*
X133695Y1240266D01*
G01D02*
X133590Y1239939D01*
G01D02*
X133486Y1239611D01*
G01X146980Y1238696D02*
X151335Y1242873D01*
G01X146744Y1238696D02*
X151383Y1243146D01*
G01X146507Y1238696D02*
X151430Y1243420D01*
G01X146269Y1238696D02*
X151479Y1243693D01*
G01X146192Y1238848D02*
X151526Y1243966D01*
G01X146239Y1239122D02*
X151574Y1244239D01*
G01X146288Y1239395D02*
X151623Y1244513D01*
G01X151670Y1244786D02*
X146336Y1239669D01*
G01X145952Y1239528D02*
X151718Y1245058D01*
G01X145278Y1239108D02*
X151765Y1245331D01*
G01X144804Y1238881D02*
X151814Y1245605D01*
G01X144399Y1238719D02*
X151861Y1245878D01*
G01X144062Y1238624D02*
X151909Y1246151D01*
G01X143726Y1238528D02*
X151958Y1246424D01*
G01X143407Y1238450D02*
X152005Y1246698D01*
G01X143143Y1238423D02*
X152053Y1246971D01*
G01X142880Y1238399D02*
X152100Y1247244D01*
G01X142617Y1238372D02*
X152149Y1247516D01*
G01X142352Y1238347D02*
X152196Y1247790D01*
G01X142119Y1238350D02*
X152244Y1248063D01*
G01X141891Y1238358D02*
X152293Y1248336D01*
G01X152340Y1248609D02*
X141668Y1238372D01*
G01X141457Y1238396D02*
X146094Y1242845D01*
G01X141247Y1238422D02*
X145522Y1242523D01*
G01X141045Y1238454D02*
X145141Y1242384D01*
G01X140849Y1238494D02*
X144760Y1242245D01*
G01X140654Y1238534D02*
X144477Y1242203D01*
G01X140468Y1238585D02*
X144205Y1242169D01*
G01X140288Y1238638D02*
X143934Y1242136D01*
G01X140107Y1238692D02*
X143665Y1242105D01*
G01X139938Y1238757D02*
X143445Y1242121D01*
G01X139771Y1238825D02*
X143226Y1242138D01*
G01X139604Y1238892D02*
X143009Y1242157D01*
G01X139448Y1238969D02*
X142823Y1242206D01*
G01X139295Y1239050D02*
X142637Y1242254D01*
G01X139143Y1239131D02*
X142459Y1242313D01*
G01X138998Y1239219D02*
X142307Y1242393D01*
G01X138861Y1239313D02*
X142154Y1242473D01*
G01X138721Y1239408D02*
X142021Y1242574D01*
G01X138588Y1239508D02*
X141902Y1242686D01*
G01X138465Y1239615D02*
X141785Y1242802D01*
G01X138340Y1239723D02*
X141698Y1242945D01*
G01X138218Y1239834D02*
X141613Y1243090D01*
G01X138108Y1239956D02*
X141553Y1243261D01*
G01X138000Y1240078D02*
X141502Y1243438D01*
G01X137890Y1240201D02*
X141473Y1243637D01*
G01X137795Y1240336D02*
X141457Y1243850D01*
G01X137700Y1240473D02*
X141469Y1244089D01*
G01X137606Y1240610D02*
X141495Y1244340D01*
G01X137523Y1240758D02*
X141613Y1244681D01*
G01X137446Y1240911D02*
X141739Y1245029D01*
G01X137369Y1241064D02*
X142401Y1245892D01*
G01X137298Y1241224D02*
X146279Y1249838D01*
G01X132993Y1239139D02*
X133486Y1239611D01*
G01X132509Y1238901D02*
X133590Y1239939D01*
G01X132123Y1238758D02*
X133695Y1240266D01*
G01X131751Y1238628D02*
X133798Y1240593D01*
G01X131443Y1238559D02*
X133902Y1240919D01*
G01X131134Y1238491D02*
X134007Y1241246D01*
G01X130826Y1238423D02*
X134111Y1241574D01*
G01X130568Y1238402D02*
X134214Y1241900D01*
G01X130310Y1238383D02*
X134318Y1242227D01*
G01X130053Y1238364D02*
X134422Y1242554D01*
G01X129795Y1238342D02*
X134526Y1242882D01*
G01X129581Y1238364D02*
X134630Y1243208D01*
G01X129366Y1238385D02*
X134734Y1243535D01*
G01X129151Y1238407D02*
X134838Y1243862D01*
G01X128937Y1238429D02*
X133985Y1243271D01*
G01X128743Y1238469D02*
X133393Y1242930D01*
G01X128568Y1238529D02*
X132980Y1242761D01*
G01X128393Y1238587D02*
X132626Y1242649D01*
G01X128216Y1238647D02*
X132356Y1242617D01*
G01X128043Y1238705D02*
X132090Y1242589D01*
G01X127894Y1238789D02*
X131866Y1242601D01*
G01X127752Y1238882D02*
X131656Y1242627D01*
G01X127610Y1238974D02*
X131462Y1242669D01*
G01X127470Y1239066D02*
X131298Y1242738D01*
G01X127329Y1239158D02*
X131146Y1242820D01*
G01X127214Y1239276D02*
X131029Y1242934D01*
G01X127104Y1239398D02*
X130929Y1243066D01*
G01X126994Y1239519D02*
X130852Y1243219D01*
G01X126884Y1239641D02*
X130801Y1243398D01*
G01X126775Y1239763D02*
X130764Y1243589D01*
G01X126692Y1239911D02*
X130757Y1243809D01*
G01X126613Y1240062D02*
X130755Y1244036D01*
G01X126533Y1240212D02*
X130784Y1244289D01*
G01X126453Y1240363D02*
X130816Y1244548D01*
G01X126373Y1240514D02*
X130860Y1244818D01*
G01X126324Y1240694D02*
X130909Y1245091D01*
G01X126275Y1240874D02*
X130956Y1245364D01*
G01X126227Y1241055D02*
X131005Y1245638D01*
G01X126178Y1241236D02*
X131052Y1245912D01*
G01X146269Y1238696D02*
X146507D01*
G01X146288Y1239395D02*
X146239Y1239122D01*
G01X146192Y1238848D02*
X146165Y1238696D01*
X146269D01*
G01X146239Y1239122D02*
X146192Y1238848D01*
G01X146744Y1238696D02*
X146980D01*
G01D02*
X147216D01*
G01X146507D02*
X146744D01*
G01X146336Y1239669D02*
X146288Y1239395D01*
G01X134111Y1241574D02*
X134007Y1241246D01*
G01D02*
X133902Y1240919D01*
G01D02*
X133798Y1240593D01*
G01D02*
X133695Y1240266D01*
G01D02*
X133590Y1239939D01*
G01D02*
X133486Y1239611D01*
G01X152659Y1251641D02*
X146870Y1246088D01*
G01X152632Y1251843D02*
X146705Y1246157D01*
G01X152603Y1252044D02*
X146535Y1246222D01*
G01X152576Y1252244D02*
X146356Y1246277D01*
G01X142905Y1246148D02*
X146679Y1249768D01*
G01X142440Y1245929D02*
X146478Y1249803D01*
G01X137239Y1241394D02*
X146078Y1249873D01*
G01X137179Y1241564D02*
X145869Y1249901D01*
G01X137125Y1241739D02*
X145645Y1249912D01*
G01X137084Y1241927D02*
X145420Y1249924D01*
G01X137045Y1242115D02*
X145196Y1249936D01*
G01X137007Y1242306D02*
X144973Y1249948D01*
G01X136988Y1242516D02*
X144728Y1249942D01*
G01X136969Y1242725D02*
X144476Y1249926D01*
G01X144222Y1249911D02*
X136951Y1242935D01*
G01X136957Y1243168D02*
X143969Y1249894D01*
G01X136962Y1243400D02*
X143715Y1249879D01*
G01X136969Y1243634D02*
X143459Y1249860D01*
G01X137001Y1243893D02*
X143162Y1249802D01*
G01X137035Y1244152D02*
X142863Y1249743D01*
G01X137079Y1244422D02*
X142565Y1249684D01*
G01X137165Y1244732D02*
X142268Y1249626D01*
G01X137252Y1245042D02*
X141925Y1249525D01*
G01X137340Y1245353D02*
X141550Y1249393D01*
G01X137427Y1245664D02*
X141176Y1249260D01*
G01X137662Y1246117D02*
X140753Y1249083D01*
G01X126136Y1241422D02*
X131100Y1246184D01*
G01X126122Y1241635D02*
X131149Y1246457D01*
G01X126107Y1241848D02*
X131196Y1246731D01*
G01X126092Y1242062D02*
X131245Y1247005D01*
G01X126077Y1242275D02*
X131292Y1247277D01*
G01X126087Y1242511D02*
X131340Y1247550D01*
G01X126111Y1242762D02*
X131389Y1247824D01*
G01X126137Y1243014D02*
X131436Y1248097D01*
G01X126161Y1243264D02*
X131485Y1248371D01*
G01X126195Y1243523D02*
X131533Y1248643D01*
G01X126243Y1243796D02*
X131580Y1248917D01*
G01X126290Y1244070D02*
X131629Y1249191D01*
G01X131676Y1249464D02*
X126339Y1244343D01*
G01X126387Y1244616D02*
X131725Y1249736D01*
G01X126434Y1244889D02*
X131773Y1250010D01*
G01X126483Y1245163D02*
X131821Y1250284D01*
G01X126530Y1245436D02*
X131869Y1250556D01*
G01X126578Y1245708D02*
X131916Y1250830D01*
G01X126625Y1245982D02*
X131965Y1251103D01*
G01X126674Y1246255D02*
X132013Y1251377D01*
G01X126290Y1244070D02*
X126243Y1243796D01*
G01X126722Y1246528D02*
X126674Y1246255D01*
G01X134214Y1241900D02*
X134111Y1241574D01*
G01X134318Y1242227D02*
X134214Y1241900D01*
G01X134422Y1242554D02*
X134318Y1242227D01*
G01X134526Y1242882D02*
X134422Y1242554D01*
G01X126674Y1246255D02*
X126625Y1245982D01*
G01X134630Y1243208D02*
X134526Y1242882D01*
G01X126625Y1245982D02*
X126578Y1245708D01*
G01X134734Y1243535D02*
X134630Y1243208D01*
G01X134838Y1243862D02*
X134734Y1243535D01*
G01X126530Y1245436D02*
X126483Y1245163D01*
G01D02*
X126434Y1244889D01*
G01X126578Y1245708D02*
X126530Y1245436D01*
G01X126434Y1244889D02*
X126387Y1244616D01*
G01X126290Y1244070D02*
X126339Y1244343D01*
G01X130956Y1245364D02*
X130909Y1245091D01*
G01D02*
X130860Y1244818D01*
G01X126387Y1244616D02*
X126339Y1244343D01*
G01X131005Y1245638D02*
X131052Y1245912D01*
G01D02*
X131100Y1246184D01*
G01X126243Y1243796D02*
X126195Y1243523D01*
G01X131005Y1245638D02*
X130956Y1245364D01*
G01X131100Y1246184D02*
X131149Y1246457D01*
G01X152659Y1251641D02*
X146870Y1246088D01*
G01X152632Y1251843D02*
X146705Y1246157D01*
G01X152603Y1252044D02*
X146535Y1246222D01*
G01X152576Y1252244D02*
X146356Y1246277D01*
G01X142905Y1246148D02*
X146679Y1249768D01*
G01X142440Y1245929D02*
X146478Y1249803D01*
G01X137239Y1241394D02*
X146078Y1249873D01*
G01X137179Y1241564D02*
X145869Y1249901D01*
G01X137125Y1241739D02*
X145645Y1249912D01*
G01X137084Y1241927D02*
X145420Y1249924D01*
G01X137045Y1242115D02*
X145196Y1249936D01*
G01X137007Y1242306D02*
X144973Y1249948D01*
G01X136988Y1242516D02*
X144728Y1249942D01*
G01X136969Y1242725D02*
X144476Y1249926D01*
G01X144222Y1249911D02*
X136951Y1242935D01*
G01X136957Y1243168D02*
X143969Y1249894D01*
G01X136962Y1243400D02*
X143715Y1249879D01*
G01X136969Y1243634D02*
X143459Y1249860D01*
G01X137001Y1243893D02*
X143162Y1249802D01*
G01X137035Y1244152D02*
X142863Y1249743D01*
G01X137079Y1244422D02*
X142565Y1249684D01*
G01X137165Y1244732D02*
X142268Y1249626D01*
G01X137252Y1245042D02*
X141925Y1249525D01*
G01X137340Y1245353D02*
X141550Y1249393D01*
G01X137427Y1245664D02*
X141176Y1249260D01*
G01X137662Y1246117D02*
X140753Y1249083D01*
G01X126136Y1241422D02*
X131100Y1246184D01*
G01X126122Y1241635D02*
X131149Y1246457D01*
G01X126107Y1241848D02*
X131196Y1246731D01*
G01X126092Y1242062D02*
X131245Y1247005D01*
G01X126077Y1242275D02*
X131292Y1247277D01*
G01X126087Y1242511D02*
X131340Y1247550D01*
G01X126111Y1242762D02*
X131389Y1247824D01*
G01X126137Y1243014D02*
X131436Y1248097D01*
G01X126161Y1243264D02*
X131485Y1248371D01*
G01X126195Y1243523D02*
X131533Y1248643D01*
G01X126243Y1243796D02*
X131580Y1248917D01*
G01X126290Y1244070D02*
X131629Y1249191D01*
G01X131676Y1249464D02*
X126339Y1244343D01*
G01X126387Y1244616D02*
X131725Y1249736D01*
G01X126434Y1244889D02*
X131773Y1250010D01*
G01X126483Y1245163D02*
X131821Y1250284D01*
G01X126530Y1245436D02*
X131869Y1250556D01*
G01X126578Y1245708D02*
X131916Y1250830D01*
G01X126625Y1245982D02*
X131965Y1251103D01*
G01X126674Y1246255D02*
X132013Y1251377D01*
G01X126290Y1244070D02*
X126243Y1243796D01*
G01X126722Y1246528D02*
X126674Y1246255D01*
G01X134214Y1241900D02*
X134111Y1241574D01*
G01X134318Y1242227D02*
X134214Y1241900D01*
G01X134422Y1242554D02*
X134318Y1242227D01*
G01X134526Y1242882D02*
X134422Y1242554D01*
G01X126674Y1246255D02*
X126625Y1245982D01*
G01X134630Y1243208D02*
X134526Y1242882D01*
G01X126625Y1245982D02*
X126578Y1245708D01*
G01X134734Y1243535D02*
X134630Y1243208D01*
G01X134838Y1243862D02*
X134734Y1243535D01*
G01X126530Y1245436D02*
X126483Y1245163D01*
G01D02*
X126434Y1244889D01*
G01X126578Y1245708D02*
X126530Y1245436D01*
G01X126434Y1244889D02*
X126387Y1244616D01*
G01X126290Y1244070D02*
X126339Y1244343D01*
G01X130956Y1245364D02*
X130909Y1245091D01*
G01D02*
X130860Y1244818D01*
G01X126387Y1244616D02*
X126339Y1244343D01*
G01X131005Y1245638D02*
X131052Y1245912D01*
G01D02*
X131100Y1246184D01*
G01X126243Y1243796D02*
X126195Y1243523D01*
G01X131005Y1245638D02*
X130956Y1245364D01*
G01X131100Y1246184D02*
X131149Y1246457D01*
G01X152549Y1252445D02*
X146170Y1246325D01*
G01X152502Y1252627D02*
X145975Y1246366D01*
G01X152434Y1252790D02*
X145771Y1246399D01*
G01X152367Y1252952D02*
X145564Y1246426D01*
G01X152301Y1253115D02*
X145348Y1246445D01*
G01X152234Y1253279D02*
X145126Y1246460D01*
G01X147889Y1249339D02*
X144899Y1246471D01*
G01X147730Y1249414D02*
X144669Y1246476D01*
G01X147571Y1249488D02*
X144435Y1246479D01*
G01X147404Y1249555D02*
X144163Y1246445D01*
G01X147225Y1249612D02*
X143889Y1246411D01*
G01X143618Y1246377D02*
X147048Y1249667D01*
G01X143345Y1246343D02*
X146870Y1249724D01*
G01X150068Y1255291D02*
X146832Y1252187D01*
G01X149907Y1255363D02*
X146638Y1252228D01*
G01X149744Y1255435D02*
X146418Y1252245D01*
G01X149583Y1255507D02*
X146200Y1252263D01*
G01X149405Y1255565D02*
X145965Y1252264D01*
G01X149215Y1255608D02*
X145724Y1252259D01*
G01X149024Y1255652D02*
X145481Y1252255D01*
G01X148831Y1255696D02*
X145230Y1252241D01*
G01X148641Y1255740D02*
X144975Y1252223D01*
G01X148450Y1255784D02*
X144718Y1252204D01*
G01X148259Y1255828D02*
X144444Y1252168D01*
G01X148042Y1255847D02*
X144170Y1252133D01*
G01X147821Y1255862D02*
X143873Y1252074D01*
G01X137901Y1246572D02*
X140204Y1248782D01*
G01X147601Y1255877D02*
X143571Y1252012D01*
G01X147379Y1255893D02*
X143238Y1251920D01*
G01X142888Y1251811D02*
X147158Y1255908D01*
G01X142513Y1251679D02*
X146936Y1255923D01*
G01X142097Y1251507D02*
X146710Y1255932D01*
G01X141648Y1251304D02*
X146466Y1255925D01*
G01X141289Y1251186D02*
X146222Y1255919D01*
G01X141225Y1251353D02*
X145978Y1255912D01*
G01X141163Y1251519D02*
X145729Y1255901D01*
G01X141100Y1251687D02*
X145469Y1255877D01*
G01X141036Y1251854D02*
X145207Y1255854D01*
G01X140974Y1252021D02*
X144945Y1255831D01*
G01X140912Y1252187D02*
X144667Y1255790D01*
G01X140848Y1252354D02*
X144384Y1255745D01*
G01X140785Y1252522D02*
X144099Y1255700D01*
G01X140723Y1252688D02*
X143791Y1255632D01*
G01X140659Y1252855D02*
X143479Y1255559D01*
G01X140597Y1253022D02*
X143156Y1255477D01*
G01X140535Y1253189D02*
X142805Y1255368D01*
G01X140471Y1253356D02*
X142454Y1255258D01*
G01X140408Y1253523D02*
X142060Y1255107D01*
G01X140346Y1253690D02*
X141660Y1254950D01*
G01X140282Y1253857D02*
X141214Y1254751D01*
G01X140220Y1254024D02*
X140752Y1254534D01*
G01X140158Y1254190D02*
X140257Y1254286D01*
G01X136070Y1251405D02*
X136063Y1251399D01*
G01X136117Y1251679D02*
X135825Y1251399D01*
G01X136164Y1251951D02*
X135589Y1251399D01*
G01X136213Y1252224D02*
X135353Y1251399D01*
G01X136261Y1252497D02*
X135116Y1251399D01*
G01X136308Y1252771D02*
X134879Y1251399D01*
G01X136356Y1253044D02*
X134643Y1251399D01*
G01X136405Y1253317D02*
X134405Y1251399D01*
G01X136452Y1253590D02*
X134168Y1251399D01*
G01X136499Y1253864D02*
X133931Y1251399D01*
G01X136547Y1254136D02*
X133695Y1251399D01*
G01X136596Y1254409D02*
X133459Y1251399D01*
G01X136643Y1254682D02*
X133221Y1251399D01*
G01X136691Y1254956D02*
X132984Y1251399D01*
G01X136740Y1255228D02*
X132746Y1251399D01*
G01X136787Y1255501D02*
X132510Y1251399D01*
G01X136632Y1255581D02*
X132273Y1251399D01*
G01X132013Y1251377D02*
X132036Y1251399D01*
G01X136395Y1255581D02*
X132036Y1251399D01*
G01X126722Y1246528D02*
X136159Y1255581D01*
G01X135923D02*
X126769Y1246801D01*
G01X135686Y1255581D02*
X126818Y1247075D01*
G01X135448Y1255581D02*
X126865Y1247348D01*
G01X135211Y1255581D02*
X126913Y1247621D01*
G01X134975Y1255581D02*
X126962Y1247893D01*
G01X134738Y1255581D02*
X127009Y1248167D01*
G01X134500Y1255581D02*
X127057Y1248441D01*
G01X134264Y1255581D02*
X127105Y1248714D01*
G01X134027Y1255581D02*
X127153Y1248986D01*
G01X133791Y1255581D02*
X127200Y1249260D01*
G01X133553Y1255581D02*
X127249Y1249533D01*
G01X133316Y1255581D02*
X127297Y1249806D01*
G01X133080Y1255581D02*
X127344Y1250079D01*
G01X132843Y1255581D02*
X127393Y1250352D01*
G01X127440Y1250626D02*
X132776Y1255745D01*
G01X132825Y1256018D02*
X127488Y1250899D01*
G01X132873Y1256291D02*
X127537Y1251171D01*
G01Y1251399D02*
X132920Y1256564D01*
G01X127299Y1251399D02*
X132969Y1256838D01*
G01X127062Y1251399D02*
X133016Y1257111D01*
G01X126826Y1251399D02*
X133065Y1257384D01*
G01X126589Y1251399D02*
X133113Y1257658D01*
G01X126351Y1251399D02*
X133162Y1257931D01*
G01X126115Y1251399D02*
X133209Y1258204D01*
G01X125878Y1251399D02*
X133256Y1258477D01*
G01X125642Y1251399D02*
X133305Y1258751D01*
G01X125405Y1251399D02*
X133353Y1259025D01*
G01X125167Y1251399D02*
X133400Y1259297D01*
G01X124931Y1251399D02*
X133449Y1259570D01*
G01X124758Y1251460D02*
X133497Y1259844D01*
G01X133545Y1260118D02*
X124805Y1251734D01*
G01X133593Y1260391D02*
X124854Y1252007D01*
G01X133642Y1260663D02*
X124901Y1252280D01*
G01X133689Y1260937D02*
X128349Y1255815D01*
G01X124950Y1252554D02*
X128105Y1255581D01*
G01X133737Y1261210D02*
X128398Y1256088D01*
G01X124998Y1252827D02*
X127869Y1255581D01*
G01X133785Y1261484D02*
X128446Y1256362D01*
G01X125045Y1253100D02*
X127632Y1255581D01*
G01X125094Y1253373D02*
X127396Y1255581D01*
G01X133833Y1261756D02*
X128493Y1256634D01*
G01X133882Y1262030D02*
X128542Y1256908D01*
G01X125141Y1253647D02*
X127158Y1255581D01*
G01X125190Y1253920D02*
X126921Y1255581D01*
G01X133631Y1262017D02*
X128589Y1257181D01*
G01X133176Y1261809D02*
X128638Y1257454D01*
G01X125238Y1254193D02*
X126685Y1255581D01*
G01X132723Y1261600D02*
X128686Y1257727D01*
G01X125287Y1254466D02*
X126448Y1255581D01*
G01X126210D02*
X125334Y1254740D01*
G01X132268Y1261391D02*
X128733Y1258001D01*
G01X131812Y1261182D02*
X128782Y1258275D01*
G01X125382Y1255013D02*
X125974Y1255581D01*
G01X125430Y1255287D02*
X125737Y1255581D01*
G01X131358Y1260973D02*
X128829Y1258547D01*
G01X125478Y1255559D02*
X125501Y1255581D01*
G01X130905Y1260764D02*
X128877Y1258820D01*
G01X130449Y1260555D02*
X128926Y1259094D01*
G01X129993Y1260346D02*
X128973Y1259367D01*
G01X129540Y1260138D02*
X129022Y1259640D01*
G01X129086Y1259929D02*
X129069Y1259913D01*
G01X140471Y1253356D02*
X140535Y1253189D01*
G01X140408Y1253523D02*
X140471Y1253356D01*
G01X140659Y1252855D02*
X140723Y1252688D01*
G01X140535Y1253189D02*
X140597Y1253022D01*
G01X140723Y1252688D02*
X140785Y1252522D01*
G01X140346Y1253690D02*
X140408Y1253523D01*
G01X140597Y1253022D02*
X140659Y1252855D01*
G01X140282Y1253857D02*
X140346Y1253690D01*
G01X140158Y1254190D02*
X140220Y1254024D01*
G01D02*
X140282Y1253857D01*
G01X141225Y1251353D02*
X141289Y1251186D01*
G01X141163Y1251519D02*
X141225Y1251353D01*
G01X140848Y1252354D02*
X140912Y1252187D01*
G01D02*
X140974Y1252021D01*
G01X140785Y1252522D02*
X140848Y1252354D01*
G01X141100Y1251687D02*
X141163Y1251519D01*
G01X141036Y1251854D02*
X141100Y1251687D01*
G01X140974Y1252021D02*
X141036Y1251854D01*
G01X131821Y1250284D02*
X131869Y1250556D01*
G01X125045Y1253100D02*
X125094Y1253373D01*
G01X131869Y1250556D02*
X131916Y1250830D01*
G01X125382Y1255013D02*
X125430Y1255287D01*
G01X125334Y1254740D02*
X125287Y1254466D01*
G01X127537Y1251399D02*
X127576D01*
X127537Y1251171D01*
G01X125382Y1255013D02*
X125334Y1254740D01*
G01X131916Y1250830D02*
X131965Y1251103D01*
G01X125141Y1253647D02*
X125190Y1253920D01*
G01X131773Y1250010D02*
X131821Y1250284D01*
G01X125238Y1254193D02*
X125287Y1254466D01*
G01X125190Y1253920D02*
X125238Y1254193D01*
G01X127440Y1250626D02*
X127393Y1250352D01*
G01X127632Y1255581D02*
X127396D01*
G01X127869D02*
X127632D01*
G01X136070Y1251405D02*
X136117Y1251679D01*
G01X124998Y1252827D02*
X125045Y1253100D01*
G01X128105Y1255581D02*
X127869D01*
G01X124950Y1252554D02*
X124998Y1252827D01*
G01X136499Y1253864D02*
X136547Y1254136D01*
G01D02*
X136596Y1254409D01*
G01X134168Y1251399D02*
X134405D01*
G01X133931D02*
X134168D01*
G01X136405Y1253317D02*
X136452Y1253590D01*
G01X133695Y1251399D02*
X133459D01*
G01X136356Y1253044D02*
X136405Y1253317D01*
G01X133695Y1251399D02*
X133931D01*
G01X134405D02*
X134643D01*
G01X136452Y1253590D02*
X136499Y1253864D01*
G01X136691Y1254956D02*
X136740Y1255228D01*
G01X135116Y1251399D02*
X135353D01*
G01X134643D02*
X134879D01*
G01D02*
X135116D01*
G01X133459D02*
X133221D01*
G01X136643Y1254682D02*
X136691Y1254956D01*
G01X136117Y1251679D02*
X136164Y1251951D01*
G01X136308Y1252771D02*
X136356Y1253044D01*
G01X132984Y1251399D02*
X132746D01*
G01X136213Y1252224D02*
X136261Y1252497D01*
G01D02*
X136308Y1252771D01*
G01X133221Y1251399D02*
X132984D01*
G01X132746D02*
X132510D01*
G01X136740Y1255228D02*
X136787Y1255501D01*
G01X132273Y1251399D02*
X132036D01*
G01X136164Y1251951D02*
X136213Y1252224D01*
G01X132510Y1251399D02*
X132273D01*
G01X136596Y1254409D02*
X136643Y1254682D01*
G01X134027Y1255581D02*
X133791D01*
G01X134264D02*
X134027D01*
G01X134738D02*
X134500D01*
G01D02*
X134264D01*
G01X131533Y1248643D02*
X131580Y1248917D01*
G01X135211Y1255581D02*
X134975D01*
G01D02*
X134738D01*
G01X131676Y1249464D02*
X131629Y1249191D01*
G01D02*
X131580Y1248917D01*
G01X133316Y1255581D02*
X133080D01*
G01X132873Y1256291D02*
X132920Y1256564D01*
G01D02*
X132969Y1256838D01*
G01X135448Y1255581D02*
X135211D01*
G01X133791D02*
X133553D01*
G01D02*
X133316D01*
G01X132776Y1255745D02*
X132825Y1256018D01*
G01D02*
X132873Y1256291D01*
G01X133080Y1255581D02*
X132843D01*
G01X131196Y1246731D02*
X131245Y1247005D01*
G01X131725Y1249736D02*
X131773Y1250010D01*
G01X136070Y1251405D02*
X136068Y1251399D01*
X136063D01*
G01X131149Y1246457D02*
X131196Y1246731D01*
G01X135825Y1251399D02*
X136063D01*
G01X125094Y1253373D02*
X125141Y1253647D01*
G01X136787Y1255501D02*
X136801Y1255581D01*
X136632D01*
G01X131676Y1249464D02*
X131725Y1249736D01*
G01X135589Y1251399D02*
X135825D01*
G01X136159Y1255581D02*
X135923D01*
G01X131436Y1248097D02*
X131485Y1248371D01*
G01X131245Y1247005D02*
X131292Y1247277D01*
G01X135353Y1251399D02*
X135589D01*
G01X135686Y1255581D02*
X135448D01*
G01X131389Y1247824D02*
X131436Y1248097D01*
G01X135923Y1255581D02*
X135686D01*
G01X131292Y1247277D02*
X131340Y1247550D01*
G01X136632Y1255581D02*
X136395D01*
G01X131340Y1247550D02*
X131389Y1247824D01*
G01X136395Y1255581D02*
X136159D01*
G01X131485Y1248371D02*
X131533Y1248643D01*
G01X127299Y1251399D02*
X127537D01*
G01Y1251171D02*
X127488Y1250899D01*
G01D02*
X127440Y1250626D01*
G01X127344Y1250079D02*
X127297Y1249806D01*
G01X127393Y1250352D02*
X127344Y1250079D01*
G01X132776Y1255745D02*
X132748Y1255581D01*
X132843D01*
G01X126115Y1251399D02*
X126351D01*
G01X125878D02*
X126115D01*
G01X125642D02*
X125878D01*
G01X126826D02*
X127062D01*
G01X126351D02*
X126589D01*
G01D02*
X126826D01*
G01X127297Y1249806D02*
X127249Y1249533D01*
G01X126818Y1247075D02*
X126769Y1246801D01*
G01X126913Y1247621D02*
X126865Y1247348D01*
G01D02*
X126818Y1247075D01*
G01X131965Y1251103D02*
X132013Y1251377D01*
G01D02*
X132017Y1251399D01*
X132036D01*
G01X126769Y1246801D02*
X126722Y1246528D01*
G01X126962Y1247893D02*
X126913Y1247621D01*
G01X127105Y1248714D02*
X127057Y1248441D01*
G01X127153Y1248986D02*
X127105Y1248714D01*
G01X127200Y1249260D02*
X127153Y1248986D01*
G01X127249Y1249533D02*
X127200Y1249260D01*
G01X127009Y1248167D02*
X126962Y1247893D01*
G01X127057Y1248441D02*
X127009Y1248167D01*
G01X127062Y1251399D02*
X127299D01*
G01X128926Y1259094D02*
X128877Y1258820D01*
G01X128926Y1259094D02*
X128973Y1259367D01*
G01X128782Y1258275D02*
X128733Y1258001D01*
G01X128877Y1258820D02*
X128829Y1258547D01*
G01X128733Y1258001D02*
X128686Y1257727D01*
G01X128973Y1259367D02*
X129022Y1259640D01*
G01X128829Y1258547D02*
X128782Y1258275D01*
G01X125405Y1251399D02*
X125642D01*
G01X129086Y1259929D02*
X129071Y1259922D01*
X129069Y1259913D01*
G01X129022Y1259640D02*
X129069Y1259913D01*
G01X124854Y1252007D02*
X124805Y1251734D01*
G01X124901Y1252280D02*
X124854Y1252007D01*
G01X124805Y1251734D02*
X124758Y1251460D01*
G01X124901Y1252280D02*
X124950Y1252554D01*
G01X125167Y1251399D02*
X125405D01*
G01X128686Y1257727D02*
X128638Y1257454D01*
G01X124758Y1251460D02*
X124747Y1251399D01*
X124931D01*
G01D02*
X125167D01*
G01X128542Y1256908D02*
X128493Y1256634D01*
G01X128589Y1257181D02*
X128542Y1256908D01*
G01X128638Y1257454D02*
X128589Y1257181D01*
G01X128398Y1256088D02*
X128349Y1255815D01*
G01X128105Y1255581D02*
X128309D01*
X128349Y1255815D01*
G01X128446Y1256362D02*
X128398Y1256088D01*
G01X128493Y1256634D02*
X128446Y1256362D01*
G01X133631Y1262017D02*
X133176Y1261809D01*
G01X133449Y1259570D02*
X133497Y1259844D01*
G01X133176Y1261809D02*
X132723Y1261600D01*
G01X127158Y1255581D02*
X126921D01*
G01X127396D02*
X127158D01*
G01X132268Y1261391D02*
X131812Y1261182D01*
G01X132723Y1261600D02*
X132268Y1261391D01*
G01X133882Y1262030D02*
X133901Y1262142D01*
X133631Y1262017D01*
G01X133545Y1260118D02*
X133593Y1260391D01*
G01D02*
X133642Y1260663D01*
G01X133497Y1259844D02*
X133545Y1260118D01*
G01X133785Y1261484D02*
X133833Y1261756D01*
G01X133737Y1261210D02*
X133785Y1261484D01*
G01X133642Y1260663D02*
X133689Y1260937D01*
G01D02*
X133737Y1261210D01*
G01X133833Y1261756D02*
X133882Y1262030D01*
G01X130449Y1260555D02*
X129993Y1260346D01*
G01X131812Y1261182D02*
X131358Y1260973D01*
G01X125430Y1255287D02*
X125478Y1255559D01*
G01D02*
X125482Y1255581D01*
X125501D01*
G01X129540Y1260138D02*
X129086Y1259929D01*
G01X129993Y1260346D02*
X129540Y1260138D01*
G01X125974Y1255581D02*
X125737D01*
G01D02*
X125501D01*
G01X126685D02*
X126448D01*
G01X131358Y1260973D02*
X130905Y1260764D01*
G01X126921Y1255581D02*
X126685D01*
G01X132969Y1256838D02*
X133016Y1257111D01*
G01X125974Y1255581D02*
X126210D01*
G01D02*
X126448D01*
G01X130905Y1260764D02*
X130449Y1260555D01*
G01X133353Y1259025D02*
X133400Y1259297D01*
G01X133162Y1257931D02*
X133209Y1258204D01*
G01X133016Y1257111D02*
X133065Y1257384D01*
G01X133305Y1258751D02*
X133353Y1259025D01*
G01X133209Y1258204D02*
X133256Y1258477D01*
G01X133400Y1259297D02*
X133449Y1259570D01*
G01X133065Y1257384D02*
X133113Y1257658D01*
G01X133256Y1258477D02*
X133305Y1258751D01*
G01X133113Y1257658D02*
X133162Y1257931D01*
G01X152549Y1252445D02*
X146170Y1246325D01*
G01X152502Y1252627D02*
X145975Y1246366D01*
G01X152434Y1252790D02*
X145771Y1246399D01*
G01X152367Y1252952D02*
X145564Y1246426D01*
G01X152301Y1253115D02*
X145348Y1246445D01*
G01X152234Y1253279D02*
X145126Y1246460D01*
G01X147889Y1249339D02*
X144899Y1246471D01*
G01X147730Y1249414D02*
X144669Y1246476D01*
G01X147571Y1249488D02*
X144435Y1246479D01*
G01X147404Y1249555D02*
X144163Y1246445D01*
G01X147225Y1249612D02*
X143889Y1246411D01*
G01X143618Y1246377D02*
X147048Y1249667D01*
G01X143345Y1246343D02*
X146870Y1249724D01*
G01X150068Y1255291D02*
X146832Y1252187D01*
G01X149907Y1255363D02*
X146638Y1252228D01*
G01X149744Y1255435D02*
X146418Y1252245D01*
G01X149583Y1255507D02*
X146200Y1252263D01*
G01X149405Y1255565D02*
X145965Y1252264D01*
G01X149215Y1255608D02*
X145724Y1252259D01*
G01X149024Y1255652D02*
X145481Y1252255D01*
G01X148831Y1255696D02*
X145230Y1252241D01*
G01X148641Y1255740D02*
X144975Y1252223D01*
G01X148450Y1255784D02*
X144718Y1252204D01*
G01X148259Y1255828D02*
X144444Y1252168D01*
G01X148042Y1255847D02*
X144170Y1252133D01*
G01X147821Y1255862D02*
X143873Y1252074D01*
G01X137901Y1246572D02*
X140204Y1248782D01*
G01X147601Y1255877D02*
X143571Y1252012D01*
G01X147379Y1255893D02*
X143238Y1251920D01*
G01X142888Y1251811D02*
X147158Y1255908D01*
G01X142513Y1251679D02*
X146936Y1255923D01*
G01X142097Y1251507D02*
X146710Y1255932D01*
G01X141648Y1251304D02*
X146466Y1255925D01*
G01X141289Y1251186D02*
X146222Y1255919D01*
G01X141225Y1251353D02*
X145978Y1255912D01*
G01X141163Y1251519D02*
X145729Y1255901D01*
G01X141100Y1251687D02*
X145469Y1255877D01*
G01X141036Y1251854D02*
X145207Y1255854D01*
G01X140974Y1252021D02*
X144945Y1255831D01*
G01X140912Y1252187D02*
X144667Y1255790D01*
G01X140848Y1252354D02*
X144384Y1255745D01*
G01X140785Y1252522D02*
X144099Y1255700D01*
G01X140723Y1252688D02*
X143791Y1255632D01*
G01X140659Y1252855D02*
X143479Y1255559D01*
G01X140597Y1253022D02*
X143156Y1255477D01*
G01X140535Y1253189D02*
X142805Y1255368D01*
G01X140471Y1253356D02*
X142454Y1255258D01*
G01X140408Y1253523D02*
X142060Y1255107D01*
G01X140346Y1253690D02*
X141660Y1254950D01*
G01X140282Y1253857D02*
X141214Y1254751D01*
G01X140220Y1254024D02*
X140752Y1254534D01*
G01X140158Y1254190D02*
X140257Y1254286D01*
G01X136070Y1251405D02*
X136063Y1251399D01*
G01X136117Y1251679D02*
X135825Y1251399D01*
G01X136164Y1251951D02*
X135589Y1251399D01*
G01X136213Y1252224D02*
X135353Y1251399D01*
G01X136261Y1252497D02*
X135116Y1251399D01*
G01X136308Y1252771D02*
X134879Y1251399D01*
G01X136356Y1253044D02*
X134643Y1251399D01*
G01X136405Y1253317D02*
X134405Y1251399D01*
G01X136452Y1253590D02*
X134168Y1251399D01*
G01X136499Y1253864D02*
X133931Y1251399D01*
G01X136547Y1254136D02*
X133695Y1251399D01*
G01X136596Y1254409D02*
X133459Y1251399D01*
G01X136643Y1254682D02*
X133221Y1251399D01*
G01X136691Y1254956D02*
X132984Y1251399D01*
G01X136740Y1255228D02*
X132746Y1251399D01*
G01X136787Y1255501D02*
X132510Y1251399D01*
G01X136632Y1255581D02*
X132273Y1251399D01*
G01X132013Y1251377D02*
X132036Y1251399D01*
G01X136395Y1255581D02*
X132036Y1251399D01*
G01X126722Y1246528D02*
X136159Y1255581D01*
G01X135923D02*
X126769Y1246801D01*
G01X135686Y1255581D02*
X126818Y1247075D01*
G01X135448Y1255581D02*
X126865Y1247348D01*
G01X135211Y1255581D02*
X126913Y1247621D01*
G01X134975Y1255581D02*
X126962Y1247893D01*
G01X134738Y1255581D02*
X127009Y1248167D01*
G01X134500Y1255581D02*
X127057Y1248441D01*
G01X134264Y1255581D02*
X127105Y1248714D01*
G01X134027Y1255581D02*
X127153Y1248986D01*
G01X133791Y1255581D02*
X127200Y1249260D01*
G01X133553Y1255581D02*
X127249Y1249533D01*
G01X133316Y1255581D02*
X127297Y1249806D01*
G01X133080Y1255581D02*
X127344Y1250079D01*
G01X132843Y1255581D02*
X127393Y1250352D01*
G01X127440Y1250626D02*
X132776Y1255745D01*
G01X132825Y1256018D02*
X127488Y1250899D01*
G01X132873Y1256291D02*
X127537Y1251171D01*
G01Y1251399D02*
X132920Y1256564D01*
G01X127299Y1251399D02*
X132969Y1256838D01*
G01X127062Y1251399D02*
X133016Y1257111D01*
G01X126826Y1251399D02*
X133065Y1257384D01*
G01X126589Y1251399D02*
X133113Y1257658D01*
G01X126351Y1251399D02*
X133162Y1257931D01*
G01X126115Y1251399D02*
X133209Y1258204D01*
G01X125878Y1251399D02*
X133256Y1258477D01*
G01X125642Y1251399D02*
X133305Y1258751D01*
G01X125405Y1251399D02*
X133353Y1259025D01*
G01X125167Y1251399D02*
X133400Y1259297D01*
G01X124931Y1251399D02*
X133449Y1259570D01*
G01X124758Y1251460D02*
X133497Y1259844D01*
G01X133545Y1260118D02*
X124805Y1251734D01*
G01X133593Y1260391D02*
X124854Y1252007D01*
G01X133642Y1260663D02*
X124901Y1252280D01*
G01X133689Y1260937D02*
X128349Y1255815D01*
G01X124950Y1252554D02*
X128105Y1255581D01*
G01X133737Y1261210D02*
X128398Y1256088D01*
G01X124998Y1252827D02*
X127869Y1255581D01*
G01X133785Y1261484D02*
X128446Y1256362D01*
G01X125045Y1253100D02*
X127632Y1255581D01*
G01X125094Y1253373D02*
X127396Y1255581D01*
G01X133833Y1261756D02*
X128493Y1256634D01*
G01X133882Y1262030D02*
X128542Y1256908D01*
G01X125141Y1253647D02*
X127158Y1255581D01*
G01X125190Y1253920D02*
X126921Y1255581D01*
G01X133631Y1262017D02*
X128589Y1257181D01*
G01X133176Y1261809D02*
X128638Y1257454D01*
G01X125238Y1254193D02*
X126685Y1255581D01*
G01X132723Y1261600D02*
X128686Y1257727D01*
G01X125287Y1254466D02*
X126448Y1255581D01*
G01X126210D02*
X125334Y1254740D01*
G01X132268Y1261391D02*
X128733Y1258001D01*
G01X131812Y1261182D02*
X128782Y1258275D01*
G01X125382Y1255013D02*
X125974Y1255581D01*
G01X125430Y1255287D02*
X125737Y1255581D01*
G01X131358Y1260973D02*
X128829Y1258547D01*
G01X125478Y1255559D02*
X125501Y1255581D01*
G01X130905Y1260764D02*
X128877Y1258820D01*
G01X130449Y1260555D02*
X128926Y1259094D01*
G01X129993Y1260346D02*
X128973Y1259367D01*
G01X129540Y1260138D02*
X129022Y1259640D01*
G01X129086Y1259929D02*
X129069Y1259913D01*
G01X140471Y1253356D02*
X140535Y1253189D01*
G01X140408Y1253523D02*
X140471Y1253356D01*
G01X140659Y1252855D02*
X140723Y1252688D01*
G01X140535Y1253189D02*
X140597Y1253022D01*
G01X140723Y1252688D02*
X140785Y1252522D01*
G01X140346Y1253690D02*
X140408Y1253523D01*
G01X140597Y1253022D02*
X140659Y1252855D01*
G01X140282Y1253857D02*
X140346Y1253690D01*
G01X140158Y1254190D02*
X140220Y1254024D01*
G01D02*
X140282Y1253857D01*
G01X141225Y1251353D02*
X141289Y1251186D01*
G01X141163Y1251519D02*
X141225Y1251353D01*
G01X140848Y1252354D02*
X140912Y1252187D01*
G01D02*
X140974Y1252021D01*
G01X140785Y1252522D02*
X140848Y1252354D01*
G01X141100Y1251687D02*
X141163Y1251519D01*
G01X141036Y1251854D02*
X141100Y1251687D01*
G01X140974Y1252021D02*
X141036Y1251854D01*
G01X131821Y1250284D02*
X131869Y1250556D01*
G01X125045Y1253100D02*
X125094Y1253373D01*
G01X131869Y1250556D02*
X131916Y1250830D01*
G01X125382Y1255013D02*
X125430Y1255287D01*
G01X125334Y1254740D02*
X125287Y1254466D01*
G01X127537Y1251399D02*
X127576D01*
X127537Y1251171D01*
G01X125382Y1255013D02*
X125334Y1254740D01*
G01X131916Y1250830D02*
X131965Y1251103D01*
G01X125141Y1253647D02*
X125190Y1253920D01*
G01X131773Y1250010D02*
X131821Y1250284D01*
G01X125238Y1254193D02*
X125287Y1254466D01*
G01X125190Y1253920D02*
X125238Y1254193D01*
G01X127440Y1250626D02*
X127393Y1250352D01*
G01X127632Y1255581D02*
X127396D01*
G01X127869D02*
X127632D01*
G01X136070Y1251405D02*
X136117Y1251679D01*
G01X124998Y1252827D02*
X125045Y1253100D01*
G01X128105Y1255581D02*
X127869D01*
G01X124950Y1252554D02*
X124998Y1252827D01*
G01X136499Y1253864D02*
X136547Y1254136D01*
G01D02*
X136596Y1254409D01*
G01X134168Y1251399D02*
X134405D01*
G01X133931D02*
X134168D01*
G01X136405Y1253317D02*
X136452Y1253590D01*
G01X133695Y1251399D02*
X133459D01*
G01X136356Y1253044D02*
X136405Y1253317D01*
G01X133695Y1251399D02*
X133931D01*
G01X134405D02*
X134643D01*
G01X136452Y1253590D02*
X136499Y1253864D01*
G01X136691Y1254956D02*
X136740Y1255228D01*
G01X135116Y1251399D02*
X135353D01*
G01X134643D02*
X134879D01*
G01D02*
X135116D01*
G01X133459D02*
X133221D01*
G01X136643Y1254682D02*
X136691Y1254956D01*
G01X136117Y1251679D02*
X136164Y1251951D01*
G01X136308Y1252771D02*
X136356Y1253044D01*
G01X132984Y1251399D02*
X132746D01*
G01X136213Y1252224D02*
X136261Y1252497D01*
G01D02*
X136308Y1252771D01*
G01X133221Y1251399D02*
X132984D01*
G01X132746D02*
X132510D01*
G01X136740Y1255228D02*
X136787Y1255501D01*
G01X132273Y1251399D02*
X132036D01*
G01X136164Y1251951D02*
X136213Y1252224D01*
G01X132510Y1251399D02*
X132273D01*
G01X136596Y1254409D02*
X136643Y1254682D01*
G01X134027Y1255581D02*
X133791D01*
G01X134264D02*
X134027D01*
G01X134738D02*
X134500D01*
G01D02*
X134264D01*
G01X131533Y1248643D02*
X131580Y1248917D01*
G01X135211Y1255581D02*
X134975D01*
G01D02*
X134738D01*
G01X131676Y1249464D02*
X131629Y1249191D01*
G01D02*
X131580Y1248917D01*
G01X133316Y1255581D02*
X133080D01*
G01X132873Y1256291D02*
X132920Y1256564D01*
G01D02*
X132969Y1256838D01*
G01X135448Y1255581D02*
X135211D01*
G01X133791D02*
X133553D01*
G01D02*
X133316D01*
G01X132776Y1255745D02*
X132825Y1256018D01*
G01D02*
X132873Y1256291D01*
G01X133080Y1255581D02*
X132843D01*
G01X131196Y1246731D02*
X131245Y1247005D01*
G01X131725Y1249736D02*
X131773Y1250010D01*
G01X136070Y1251405D02*
X136068Y1251399D01*
X136063D01*
G01X131149Y1246457D02*
X131196Y1246731D01*
G01X135825Y1251399D02*
X136063D01*
G01X125094Y1253373D02*
X125141Y1253647D01*
G01X136787Y1255501D02*
X136801Y1255581D01*
X136632D01*
G01X131676Y1249464D02*
X131725Y1249736D01*
G01X135589Y1251399D02*
X135825D01*
G01X136159Y1255581D02*
X135923D01*
G01X131436Y1248097D02*
X131485Y1248371D01*
G01X131245Y1247005D02*
X131292Y1247277D01*
G01X135353Y1251399D02*
X135589D01*
G01X135686Y1255581D02*
X135448D01*
G01X131389Y1247824D02*
X131436Y1248097D01*
G01X135923Y1255581D02*
X135686D01*
G01X131292Y1247277D02*
X131340Y1247550D01*
G01X136632Y1255581D02*
X136395D01*
G01X131340Y1247550D02*
X131389Y1247824D01*
G01X136395Y1255581D02*
X136159D01*
G01X131485Y1248371D02*
X131533Y1248643D01*
G01X127299Y1251399D02*
X127537D01*
G01Y1251171D02*
X127488Y1250899D01*
G01D02*
X127440Y1250626D01*
G01X127344Y1250079D02*
X127297Y1249806D01*
G01X127393Y1250352D02*
X127344Y1250079D01*
G01X132776Y1255745D02*
X132748Y1255581D01*
X132843D01*
G01X126115Y1251399D02*
X126351D01*
G01X125878D02*
X126115D01*
G01X125642D02*
X125878D01*
G01X126826D02*
X127062D01*
G01X126351D02*
X126589D01*
G01D02*
X126826D01*
G01X127297Y1249806D02*
X127249Y1249533D01*
G01X126818Y1247075D02*
X126769Y1246801D01*
G01X126913Y1247621D02*
X126865Y1247348D01*
G01D02*
X126818Y1247075D01*
G01X131965Y1251103D02*
X132013Y1251377D01*
G01D02*
X132017Y1251399D01*
X132036D01*
G01X126769Y1246801D02*
X126722Y1246528D01*
G01X126962Y1247893D02*
X126913Y1247621D01*
G01X127105Y1248714D02*
X127057Y1248441D01*
G01X127153Y1248986D02*
X127105Y1248714D01*
G01X127200Y1249260D02*
X127153Y1248986D01*
G01X127249Y1249533D02*
X127200Y1249260D01*
G01X127009Y1248167D02*
X126962Y1247893D01*
G01X127057Y1248441D02*
X127009Y1248167D01*
G01X127062Y1251399D02*
X127299D01*
G01X128926Y1259094D02*
X128877Y1258820D01*
G01X128926Y1259094D02*
X128973Y1259367D01*
G01X128782Y1258275D02*
X128733Y1258001D01*
G01X128877Y1258820D02*
X128829Y1258547D01*
G01X128733Y1258001D02*
X128686Y1257727D01*
G01X128973Y1259367D02*
X129022Y1259640D01*
G01X128829Y1258547D02*
X128782Y1258275D01*
G01X125405Y1251399D02*
X125642D01*
G01X129086Y1259929D02*
X129071Y1259922D01*
X129069Y1259913D01*
G01X129022Y1259640D02*
X129069Y1259913D01*
G01X124854Y1252007D02*
X124805Y1251734D01*
G01X124901Y1252280D02*
X124854Y1252007D01*
G01X124805Y1251734D02*
X124758Y1251460D01*
G01X124901Y1252280D02*
X124950Y1252554D01*
G01X125167Y1251399D02*
X125405D01*
G01X128686Y1257727D02*
X128638Y1257454D01*
G01X124758Y1251460D02*
X124747Y1251399D01*
X124931D01*
G01D02*
X125167D01*
G01X128542Y1256908D02*
X128493Y1256634D01*
G01X128589Y1257181D02*
X128542Y1256908D01*
G01X128638Y1257454D02*
X128589Y1257181D01*
G01X128398Y1256088D02*
X128349Y1255815D01*
G01X128105Y1255581D02*
X128309D01*
X128349Y1255815D01*
G01X128446Y1256362D02*
X128398Y1256088D01*
G01X128493Y1256634D02*
X128446Y1256362D01*
G01X133631Y1262017D02*
X133176Y1261809D01*
G01X133449Y1259570D02*
X133497Y1259844D01*
G01X133176Y1261809D02*
X132723Y1261600D01*
G01X127158Y1255581D02*
X126921D01*
G01X127396D02*
X127158D01*
G01X132268Y1261391D02*
X131812Y1261182D01*
G01X132723Y1261600D02*
X132268Y1261391D01*
G01X133882Y1262030D02*
X133901Y1262142D01*
X133631Y1262017D01*
G01X133545Y1260118D02*
X133593Y1260391D01*
G01D02*
X133642Y1260663D01*
G01X133497Y1259844D02*
X133545Y1260118D01*
G01X133785Y1261484D02*
X133833Y1261756D01*
G01X133737Y1261210D02*
X133785Y1261484D01*
G01X133642Y1260663D02*
X133689Y1260937D01*
G01D02*
X133737Y1261210D01*
G01X133833Y1261756D02*
X133882Y1262030D01*
G01X130449Y1260555D02*
X129993Y1260346D01*
G01X131812Y1261182D02*
X131358Y1260973D01*
G01X125430Y1255287D02*
X125478Y1255559D01*
G01D02*
X125482Y1255581D01*
X125501D01*
G01X129540Y1260138D02*
X129086Y1259929D01*
G01X129993Y1260346D02*
X129540Y1260138D01*
G01X125974Y1255581D02*
X125737D01*
G01D02*
X125501D01*
G01X126685D02*
X126448D01*
G01X131358Y1260973D02*
X130905Y1260764D01*
G01X126921Y1255581D02*
X126685D01*
G01X132969Y1256838D02*
X133016Y1257111D01*
G01X125974Y1255581D02*
X126210D01*
G01D02*
X126448D01*
G01X130905Y1260764D02*
X130449Y1260555D01*
G01X133353Y1259025D02*
X133400Y1259297D01*
G01X133162Y1257931D02*
X133209Y1258204D01*
G01X133016Y1257111D02*
X133065Y1257384D01*
G01X133305Y1258751D02*
X133353Y1259025D01*
G01X133209Y1258204D02*
X133256Y1258477D01*
G01X133400Y1259297D02*
X133449Y1259570D01*
G01X133065Y1257384D02*
X133113Y1257658D01*
G01X133256Y1258477D02*
X133305Y1258751D01*
G01X133113Y1257658D02*
X133162Y1257931D01*
G01X151019Y574289D02*
X154942Y621205D01*
G02X166712I5885J-492D01*
G01X170635Y574289D01*
G02X151019I-9808J-820D01*
G01X150533Y1238696D02*
X150616Y1238776D01*
G01X150296Y1238696D02*
X150665Y1239050D01*
G01X150059Y1238696D02*
X150713Y1239324D01*
G01X149823Y1238696D02*
X150760Y1239596D01*
G01X149585Y1238696D02*
X150807Y1239868D01*
G01X149348Y1238696D02*
X150856Y1240142D01*
G01X149111Y1238696D02*
X150904Y1240416D01*
G01X148875Y1238696D02*
X150951Y1240688D01*
G01X148639Y1238696D02*
X151000Y1240961D01*
G01X148401Y1238696D02*
X151048Y1241235D01*
G01X148164Y1238696D02*
X151095Y1241509D01*
G01X147927Y1238696D02*
X151144Y1241781D01*
G01X147691Y1238696D02*
X151191Y1242054D01*
G01X147453Y1238696D02*
X151239Y1242327D01*
G01X147216Y1238696D02*
X151288Y1242601D01*
G01X149348Y1238696D02*
X149585D01*
G01X148875D02*
X149111D01*
G01D02*
X149348D01*
G01X148401D02*
X148639D01*
G01D02*
X148875D01*
G01X150296D02*
X150533D01*
G01D02*
X150603D01*
X150616Y1238776D01*
G01X148164Y1238696D02*
X148401D01*
G01X149585D02*
X149823D01*
G01X150059D02*
X150296D01*
G01X149823D02*
X150059D01*
G01X147691D02*
X147927D01*
G01X147453D02*
X147691D01*
G01X147927D02*
X148164D01*
G01X147216D02*
X147453D01*
G01X150616Y1238776D02*
X150665Y1239050D01*
G01X150807Y1239868D02*
X150856Y1240142D01*
G01X150904Y1240416D02*
X150951Y1240688D01*
G01X150856Y1240142D02*
X150904Y1240416D01*
G01X150760Y1239596D02*
X150807Y1239868D01*
G01X150665Y1239050D02*
X150713Y1239324D01*
G01D02*
X150760Y1239596D01*
G01X151000Y1240961D02*
X151048Y1241235D01*
G01X150951Y1240688D02*
X151000Y1240961D01*
G01X151048Y1241235D02*
X151095Y1241509D01*
G01X150533Y1238696D02*
X150616Y1238776D01*
G01X150296Y1238696D02*
X150665Y1239050D01*
G01X150059Y1238696D02*
X150713Y1239324D01*
G01X149823Y1238696D02*
X150760Y1239596D01*
G01X149585Y1238696D02*
X150807Y1239868D01*
G01X149348Y1238696D02*
X150856Y1240142D01*
G01X149111Y1238696D02*
X150904Y1240416D01*
G01X148875Y1238696D02*
X150951Y1240688D01*
G01X148639Y1238696D02*
X151000Y1240961D01*
G01X148401Y1238696D02*
X151048Y1241235D01*
G01X148164Y1238696D02*
X151095Y1241509D01*
G01X147927Y1238696D02*
X151144Y1241781D01*
G01X147691Y1238696D02*
X151191Y1242054D01*
G01X147453Y1238696D02*
X151239Y1242327D01*
G01X147216Y1238696D02*
X151288Y1242601D01*
G01X149348Y1238696D02*
X149585D01*
G01X148875D02*
X149111D01*
G01D02*
X149348D01*
G01X148401D02*
X148639D01*
G01D02*
X148875D01*
G01X150296D02*
X150533D01*
G01D02*
X150603D01*
X150616Y1238776D01*
G01X148164Y1238696D02*
X148401D01*
G01X149585D02*
X149823D01*
G01X150059D02*
X150296D01*
G01X149823D02*
X150059D01*
G01X147691D02*
X147927D01*
G01X147453D02*
X147691D01*
G01X147927D02*
X148164D01*
G01X147216D02*
X147453D01*
G01X150616Y1238776D02*
X150665Y1239050D01*
G01X150807Y1239868D02*
X150856Y1240142D01*
G01X150904Y1240416D02*
X150951Y1240688D01*
G01X150856Y1240142D02*
X150904Y1240416D01*
G01X150760Y1239596D02*
X150807Y1239868D01*
G01X150665Y1239050D02*
X150713Y1239324D01*
G01D02*
X150760Y1239596D01*
G01X151000Y1240961D02*
X151048Y1241235D01*
G01X150951Y1240688D02*
X151000Y1240961D01*
G01X151048Y1241235D02*
X151095Y1241509D01*
G01X152388Y1248883D02*
X147054Y1243767D01*
G01X152436Y1249156D02*
X147102Y1244040D01*
G01X152484Y1249429D02*
X147151Y1244312D01*
G01X152531Y1249701D02*
X147198Y1244585D01*
G01X152579Y1249975D02*
X147246Y1244859D01*
G01X152605Y1250226D02*
X147295Y1245132D01*
G01X152624Y1250472D02*
X147342Y1245405D01*
G01X152644Y1250718D02*
X147389Y1245678D01*
G01X152664Y1250965D02*
X147314Y1245832D01*
G01X152685Y1251213D02*
X147171Y1245924D01*
G01X152686Y1251441D02*
X147022Y1246007D01*
G01X151623Y1244513D02*
X151670Y1244786D01*
G01D02*
X151718Y1245058D01*
G01D02*
X151765Y1245331D01*
G01X151526Y1243966D02*
X151574Y1244239D01*
G01X151479Y1243693D02*
X151526Y1243966D01*
G01X151574Y1244239D02*
X151623Y1244513D01*
G01X151430Y1243420D02*
X151479Y1243693D01*
G01X151909Y1246151D02*
X151958Y1246424D01*
G01X151861Y1245878D02*
X151909Y1246151D01*
G01X151765Y1245331D02*
X151814Y1245605D01*
G01D02*
X151861Y1245878D01*
G01X151383Y1243146D02*
X151430Y1243420D01*
G01X151239Y1242327D02*
X151288Y1242601D01*
G01X151335Y1242873D02*
X151383Y1243146D01*
G01X151191Y1242054D02*
X151239Y1242327D01*
G01X151288Y1242601D02*
X151335Y1242873D01*
G01X151095Y1241509D02*
X151144Y1241781D01*
G01D02*
X151191Y1242054D01*
G01X147295Y1245132D02*
X147246Y1244859D01*
G01D02*
X147198Y1244585D01*
G01X147389Y1245678D02*
X147342Y1245405D01*
G01D02*
X147295Y1245132D01*
G01X147102Y1244040D02*
X147054Y1243767D01*
G01X147198Y1244585D02*
X147151Y1244312D01*
G01D02*
X147102Y1244040D01*
G01X152388Y1248883D02*
X147054Y1243767D01*
G01X152436Y1249156D02*
X147102Y1244040D01*
G01X152484Y1249429D02*
X147151Y1244312D01*
G01X152531Y1249701D02*
X147198Y1244585D01*
G01X152579Y1249975D02*
X147246Y1244859D01*
G01X152605Y1250226D02*
X147295Y1245132D01*
G01X152624Y1250472D02*
X147342Y1245405D01*
G01X152644Y1250718D02*
X147389Y1245678D01*
G01X152664Y1250965D02*
X147314Y1245832D01*
G01X152685Y1251213D02*
X147171Y1245924D01*
G01X152686Y1251441D02*
X147022Y1246007D01*
G01X151623Y1244513D02*
X151670Y1244786D01*
G01D02*
X151718Y1245058D01*
G01D02*
X151765Y1245331D01*
G01X151526Y1243966D02*
X151574Y1244239D01*
G01X151479Y1243693D02*
X151526Y1243966D01*
G01X151574Y1244239D02*
X151623Y1244513D01*
G01X151430Y1243420D02*
X151479Y1243693D01*
G01X151909Y1246151D02*
X151958Y1246424D01*
G01X151861Y1245878D02*
X151909Y1246151D01*
G01X151765Y1245331D02*
X151814Y1245605D01*
G01D02*
X151861Y1245878D01*
G01X151383Y1243146D02*
X151430Y1243420D01*
G01X151239Y1242327D02*
X151288Y1242601D01*
G01X151335Y1242873D02*
X151383Y1243146D01*
G01X151191Y1242054D02*
X151239Y1242327D01*
G01X151288Y1242601D02*
X151335Y1242873D01*
G01X151095Y1241509D02*
X151144Y1241781D01*
G01D02*
X151191Y1242054D01*
G01X147295Y1245132D02*
X147246Y1244859D01*
G01D02*
X147198Y1244585D01*
G01X147389Y1245678D02*
X147342Y1245405D01*
G01D02*
X147295Y1245132D01*
G01X147102Y1244040D02*
X147054Y1243767D01*
G01X147198Y1244585D02*
X147151Y1244312D01*
G01D02*
X147102Y1244040D01*
G01X152167Y1253442D02*
X148061Y1249503D01*
G01X152089Y1253595D02*
X148110Y1249777D01*
G01X151989Y1253725D02*
X148157Y1250050D01*
G01X151887Y1253855D02*
X148186Y1250305D01*
G01X151785Y1253986D02*
X148207Y1250552D01*
G01X151685Y1254115D02*
X148186Y1250758D01*
G01X151583Y1254245D02*
X148161Y1250963D01*
G01X151482Y1254376D02*
X148103Y1251134D01*
G01X151355Y1254481D02*
X148045Y1251306D01*
G01X151223Y1254581D02*
X147956Y1251448D01*
G01X151091Y1254681D02*
X147866Y1251587D01*
G01X150958Y1254781D02*
X147754Y1251708D01*
G01X150825Y1254882D02*
X147631Y1251818D01*
G01X150694Y1254981D02*
X147501Y1251920D01*
G01X150555Y1255076D02*
X147349Y1252000D01*
G01X150392Y1255148D02*
X147194Y1252080D01*
G01X150230Y1255220D02*
X147017Y1252137D01*
G01X152196Y1247790D02*
X152244Y1248063D01*
G01X152531Y1249701D02*
X152579Y1249975D01*
G01X152484Y1249429D02*
X152531Y1249701D01*
G01X152436Y1249156D02*
X152484Y1249429D01*
G01X152388Y1248883D02*
X152436Y1249156D01*
G01X152293Y1248336D02*
X152340Y1248609D01*
G01X152244Y1248063D02*
X152293Y1248336D01*
G01X152340Y1248609D02*
X152388Y1248883D01*
G01X151958Y1246424D02*
X152005Y1246698D01*
G01X152053Y1246971D02*
X152100Y1247244D01*
G01D02*
X152149Y1247516D01*
G01D02*
X152196Y1247790D01*
G01X152005Y1246698D02*
X152053Y1246971D01*
G01X148157Y1250050D02*
X148110Y1249777D01*
G01D02*
X148061Y1249503D01*
G01X152167Y1253442D02*
X148061Y1249503D01*
G01X152089Y1253595D02*
X148110Y1249777D01*
G01X151989Y1253725D02*
X148157Y1250050D01*
G01X151887Y1253855D02*
X148186Y1250305D01*
G01X151785Y1253986D02*
X148207Y1250552D01*
G01X151685Y1254115D02*
X148186Y1250758D01*
G01X151583Y1254245D02*
X148161Y1250963D01*
G01X151482Y1254376D02*
X148103Y1251134D01*
G01X151355Y1254481D02*
X148045Y1251306D01*
G01X151223Y1254581D02*
X147956Y1251448D01*
G01X151091Y1254681D02*
X147866Y1251587D01*
G01X150958Y1254781D02*
X147754Y1251708D01*
G01X150825Y1254882D02*
X147631Y1251818D01*
G01X150694Y1254981D02*
X147501Y1251920D01*
G01X150555Y1255076D02*
X147349Y1252000D01*
G01X150392Y1255148D02*
X147194Y1252080D01*
G01X150230Y1255220D02*
X147017Y1252137D01*
G01X152196Y1247790D02*
X152244Y1248063D01*
G01X152531Y1249701D02*
X152579Y1249975D01*
G01X152484Y1249429D02*
X152531Y1249701D01*
G01X152436Y1249156D02*
X152484Y1249429D01*
G01X152388Y1248883D02*
X152436Y1249156D01*
G01X152293Y1248336D02*
X152340Y1248609D01*
G01X152244Y1248063D02*
X152293Y1248336D01*
G01X152340Y1248609D02*
X152388Y1248883D01*
G01X151958Y1246424D02*
X152005Y1246698D01*
G01X152053Y1246971D02*
X152100Y1247244D01*
G01D02*
X152149Y1247516D01*
G01D02*
X152196Y1247790D01*
G01X152005Y1246698D02*
X152053Y1246971D01*
G01X148157Y1250050D02*
X148110Y1249777D01*
G01D02*
X148061Y1249503D01*
G01X170276Y111457D02*
G02X176181I2953J0D01*
G02X170276I-2952J0D01*
G01Y474843D02*
G02X176181I2953J0D01*
G02X170276I-2952J0D01*
G01Y838228D02*
G02X176181I2953J0D01*
G02X170276I-2952J0D01*
G01Y1201614D02*
G02X176181I2953J0D01*
G02X170276I-2952J0D01*
G01X329322Y-314459D02*
Y-319459D01*
G01X327865Y-314459D02*
X330779D01*
G01X335689Y-319459D02*
X333155D01*
Y-314459D01*
X335689D01*
G01X334675Y-316876D02*
X333155D01*
G01X338255Y-314459D02*
Y-319459D01*
X340789D01*
G01X344622Y-319626D02*
X344495Y-319542D01*
Y-319376D01*
X344622Y-319292D01*
X344749Y-319376D01*
Y-319542D01*
X344622Y-319626D01*
G01Y-317376D02*
X344495Y-317292D01*
Y-317126D01*
X344622Y-317042D01*
X344749Y-317126D01*
Y-317292D01*
X344622Y-317376D01*
G01X349405Y-321126D02*
X348772Y-320292D01*
X348455Y-319459D01*
Y-316126D01*
X348772Y-315292D01*
X349405Y-314459D01*
G01X354822D02*
X354315Y-314626D01*
X353935Y-315042D01*
X353682Y-315542D01*
X353492Y-316209D01*
X353429Y-316959D01*
X353492Y-317709D01*
X353682Y-318376D01*
X353935Y-318876D01*
X354315Y-319292D01*
X354822Y-319459D01*
X355329Y-319292D01*
X355709Y-318876D01*
X355962Y-318376D01*
X356152Y-317709D01*
X356215Y-316959D01*
X356152Y-316209D01*
X355962Y-315542D01*
X355709Y-315042D01*
X355329Y-314626D01*
X354822Y-314459D01*
G01X358529Y-318459D02*
X358909Y-319042D01*
X359415Y-319376D01*
X359985Y-319459D01*
X360492Y-319376D01*
X360999Y-318959D01*
X361315Y-318459D01*
X361379Y-317959D01*
X361252Y-317376D01*
X360809Y-316959D01*
X360365Y-316792D01*
X359795D01*
G01X360365D02*
X360745Y-316542D01*
X361062Y-316126D01*
X361189Y-315626D01*
X361062Y-315126D01*
X360745Y-314709D01*
X360175Y-314459D01*
X359605Y-314542D01*
X359035Y-314876D01*
G01X365339Y-321126D02*
X365972Y-320292D01*
X366289Y-319459D01*
Y-316126D01*
X365972Y-315292D01*
X365339Y-314459D01*
G01X368729Y-318459D02*
X369109Y-319042D01*
X369615Y-319376D01*
X370185Y-319459D01*
X370692Y-319376D01*
X371199Y-318959D01*
X371515Y-318459D01*
X371579Y-317959D01*
X371452Y-317376D01*
X371009Y-316959D01*
X370565Y-316792D01*
X369995D01*
G01X370565D02*
X370945Y-316542D01*
X371262Y-316126D01*
X371389Y-315626D01*
X371262Y-315126D01*
X370945Y-314709D01*
X370375Y-314459D01*
X369805Y-314542D01*
X369235Y-314876D01*
G01X374019Y-315292D02*
X374399Y-314792D01*
X374842Y-314542D01*
X375349Y-314459D01*
X375982Y-314626D01*
X376425Y-315042D01*
X376552Y-315542D01*
X376489Y-316042D01*
X376235Y-316459D01*
X374969Y-317292D01*
X374399Y-317876D01*
X374019Y-318709D01*
X373892Y-319459D01*
X376552D01*
G01X380195D02*
X380322Y-318376D01*
X380512Y-317459D01*
X380765Y-316626D01*
X381082Y-315709D01*
X381589Y-314459D01*
X379055D01*
G01X384599Y-317792D02*
X386245D01*
G01X389319Y-315292D02*
X389699Y-314792D01*
X390142Y-314542D01*
X390649Y-314459D01*
X391282Y-314626D01*
X391725Y-315042D01*
X391852Y-315542D01*
X391789Y-316042D01*
X391535Y-316459D01*
X390269Y-317292D01*
X389699Y-317876D01*
X389319Y-318709D01*
X389192Y-319459D01*
X391852D01*
G01X394229Y-318459D02*
X394609Y-319042D01*
X395115Y-319376D01*
X395685Y-319459D01*
X396192Y-319376D01*
X396699Y-318959D01*
X397015Y-318459D01*
X397079Y-317959D01*
X396952Y-317376D01*
X396509Y-316959D01*
X396065Y-316792D01*
X395495D01*
G01X396065D02*
X396445Y-316542D01*
X396762Y-316126D01*
X396889Y-315626D01*
X396762Y-315126D01*
X396445Y-314709D01*
X395875Y-314459D01*
X395305Y-314542D01*
X394735Y-314876D01*
G01X401482Y-319459D02*
Y-314459D01*
X399139Y-318042D01*
X402305D01*
G01X404429Y-318709D02*
X404809Y-319126D01*
X405252Y-319376D01*
X405822Y-319459D01*
X406392Y-319292D01*
X406835Y-318959D01*
X407152Y-318376D01*
X407215Y-317709D01*
X407089Y-317042D01*
X406772Y-316626D01*
X406329Y-316292D01*
X405885Y-316209D01*
X405442Y-316292D01*
X404872Y-316626D01*
X405062Y-314459D01*
X406772D01*
G01X414819Y-319459D02*
Y-314459D01*
X417225D01*
G01X416339Y-316876D02*
X414819D01*
G01X419539Y-319459D02*
X421122Y-314459D01*
X422705Y-319459D01*
G01X422135Y-317709D02*
X420109D01*
G01X424892Y-319459D02*
X427552Y-314459D01*
G01X424892D02*
X427552Y-319459D01*
G01X431322Y-319626D02*
X431195Y-319542D01*
Y-319376D01*
X431322Y-319292D01*
X431449Y-319376D01*
Y-319542D01*
X431322Y-319626D01*
G01Y-317376D02*
X431195Y-317292D01*
Y-317126D01*
X431322Y-317042D01*
X431449Y-317126D01*
Y-317292D01*
X431322Y-317376D01*
G01X436105Y-321126D02*
X435472Y-320292D01*
X435155Y-319459D01*
Y-316126D01*
X435472Y-315292D01*
X436105Y-314459D01*
G01X441522D02*
X441015Y-314626D01*
X440635Y-315042D01*
X440382Y-315542D01*
X440192Y-316209D01*
X440129Y-316959D01*
X440192Y-317709D01*
X440382Y-318376D01*
X440635Y-318876D01*
X441015Y-319292D01*
X441522Y-319459D01*
X442029Y-319292D01*
X442409Y-318876D01*
X442662Y-318376D01*
X442852Y-317709D01*
X442915Y-316959D01*
X442852Y-316209D01*
X442662Y-315542D01*
X442409Y-315042D01*
X442029Y-314626D01*
X441522Y-314459D01*
G01X445229Y-318459D02*
X445609Y-319042D01*
X446115Y-319376D01*
X446685Y-319459D01*
X447192Y-319376D01*
X447699Y-318959D01*
X448015Y-318459D01*
X448079Y-317959D01*
X447952Y-317376D01*
X447509Y-316959D01*
X447065Y-316792D01*
X446495D01*
G01X447065D02*
X447445Y-316542D01*
X447762Y-316126D01*
X447889Y-315626D01*
X447762Y-315126D01*
X447445Y-314709D01*
X446875Y-314459D01*
X446305Y-314542D01*
X445735Y-314876D01*
G01X452039Y-321126D02*
X452672Y-320292D01*
X452989Y-319459D01*
Y-316126D01*
X452672Y-315292D01*
X452039Y-314459D01*
G01X455429Y-318459D02*
X455809Y-319042D01*
X456315Y-319376D01*
X456885Y-319459D01*
X457392Y-319376D01*
X457899Y-318959D01*
X458215Y-318459D01*
X458279Y-317959D01*
X458152Y-317376D01*
X457709Y-316959D01*
X457265Y-316792D01*
X456695D01*
G01X457265D02*
X457645Y-316542D01*
X457962Y-316126D01*
X458089Y-315626D01*
X457962Y-315126D01*
X457645Y-314709D01*
X457075Y-314459D01*
X456505Y-314542D01*
X455935Y-314876D01*
G01X460845Y-318876D02*
X461289Y-319292D01*
X461795Y-319459D01*
X462302Y-319292D01*
X462745Y-318792D01*
X463062Y-318042D01*
X463189Y-317292D01*
Y-316376D01*
X463062Y-315626D01*
X462745Y-314959D01*
X462365Y-314626D01*
X461922Y-314459D01*
X461415Y-314626D01*
X461035Y-314959D01*
X460782Y-315459D01*
X460655Y-316126D01*
X460782Y-316709D01*
X461099Y-317292D01*
X461479Y-317626D01*
X461922Y-317709D01*
X462429Y-317542D01*
X462809Y-317126D01*
X463189Y-316376D01*
G01X466895Y-319459D02*
X467022Y-318376D01*
X467212Y-317459D01*
X467465Y-316626D01*
X467782Y-315709D01*
X468289Y-314459D01*
X465755D01*
G01X471299Y-317792D02*
X472945D01*
G01X475829Y-318459D02*
X476209Y-319042D01*
X476715Y-319376D01*
X477285Y-319459D01*
X477792Y-319376D01*
X478299Y-318959D01*
X478615Y-318459D01*
X478679Y-317959D01*
X478552Y-317376D01*
X478109Y-316959D01*
X477665Y-316792D01*
X477095D01*
G01X477665D02*
X478045Y-316542D01*
X478362Y-316126D01*
X478489Y-315626D01*
X478362Y-315126D01*
X478045Y-314709D01*
X477475Y-314459D01*
X476905Y-314542D01*
X476335Y-314876D01*
G01X481119Y-317376D02*
X481562Y-316792D01*
X481942Y-316459D01*
X482449Y-316292D01*
X482892Y-316459D01*
X483209Y-316792D01*
X483462Y-317292D01*
X483525Y-317876D01*
X483462Y-318376D01*
X483209Y-318876D01*
X482829Y-319292D01*
X482385Y-319459D01*
X481879Y-319292D01*
X481435Y-318792D01*
X481182Y-318042D01*
X481119Y-317209D01*
X481245Y-316126D01*
X481435Y-315542D01*
X481752Y-314959D01*
X482195Y-314542D01*
X482639Y-314459D01*
X483082Y-314626D01*
X483399Y-315042D01*
G01X487422Y-319459D02*
Y-314459D01*
X486662Y-315459D01*
G01Y-319459D02*
X488182D01*
G01X493282D02*
Y-314459D01*
X490939Y-318042D01*
X494105D01*
G01X317322Y-249459D02*
Y-324459D01*
X817322D01*
Y-249459D01*
X317322D01*
G01X512322D02*
Y-324459D01*
G01Y-299459D02*
X615322D01*
Y-274459D01*
G01X512322D02*
X615322D01*
G01X622829Y-309459D02*
Y-304459D01*
X624095D01*
X624602Y-304709D01*
X624982Y-305042D01*
X625299Y-305542D01*
X625552Y-306126D01*
X625615Y-306959D01*
X625552Y-307792D01*
X625299Y-308376D01*
X624982Y-308876D01*
X624602Y-309209D01*
X624095Y-309459D01*
X622829D01*
G01X627739D02*
X629322Y-304459D01*
X630905Y-309459D01*
G01X630335Y-307709D02*
X628309D01*
G01X634422Y-304459D02*
Y-309459D01*
G01X632965Y-304459D02*
X635879D01*
G01X640789Y-309459D02*
X638255D01*
Y-304459D01*
X640789D01*
G01X639775Y-306876D02*
X638255D01*
G01X644622Y-309626D02*
X644495Y-309542D01*
Y-309376D01*
X644622Y-309292D01*
X644749Y-309376D01*
Y-309542D01*
X644622Y-309626D01*
G01Y-307376D02*
X644495Y-307292D01*
Y-307126D01*
X644622Y-307042D01*
X644749Y-307126D01*
Y-307292D01*
X644622Y-307376D01*
G01X617322Y-249459D02*
Y-324459D01*
G01X615322Y-249459D02*
Y-324459D01*
G01X622955Y-284459D02*
Y-279459D01*
X624475D01*
X624982Y-279709D01*
X625362Y-280292D01*
X625489Y-280959D01*
X625362Y-281626D01*
X625045Y-282126D01*
X624475Y-282376D01*
X622955D01*
G01X628182Y-284626D02*
X630462Y-279459D01*
G01X632965Y-284459D02*
Y-279459D01*
X635879Y-284459D01*
Y-279459D01*
G01X639522Y-284626D02*
X639395Y-284542D01*
Y-284376D01*
X639522Y-284292D01*
X639649Y-284376D01*
Y-284542D01*
X639522Y-284626D01*
G01Y-282376D02*
X639395Y-282292D01*
Y-282126D01*
X639522Y-282042D01*
X639649Y-282126D01*
Y-282292D01*
X639522Y-282376D01*
G01X617322Y-299459D02*
X817322D01*
G01X622955Y-259459D02*
Y-254459D01*
X624475D01*
X624982Y-254709D01*
X625362Y-255292D01*
X625489Y-255959D01*
X625362Y-256626D01*
X625045Y-257126D01*
X624475Y-257376D01*
X622955D01*
G01X628055Y-259459D02*
Y-254459D01*
X629639D01*
X630145Y-254709D01*
X630462Y-255042D01*
X630589Y-255709D01*
X630462Y-256376D01*
X630082Y-256792D01*
X629639Y-257042D01*
X628055D01*
G01X629639D02*
X630589Y-259459D01*
G01X634422D02*
X633915Y-259376D01*
X633472Y-259042D01*
X633092Y-258542D01*
X632839Y-257959D01*
X632712Y-257292D01*
Y-256626D01*
X632839Y-255959D01*
X633092Y-255376D01*
X633472Y-254876D01*
X633915Y-254542D01*
X634422Y-254459D01*
X634929Y-254542D01*
X635372Y-254876D01*
X635752Y-255376D01*
X636005Y-255959D01*
X636132Y-256626D01*
Y-257292D01*
X636005Y-257959D01*
X635752Y-258542D01*
X635372Y-259042D01*
X634929Y-259376D01*
X634422Y-259459D01*
G01X638255Y-258459D02*
X638572Y-258959D01*
X638952Y-259292D01*
X639395Y-259459D01*
X639902Y-259292D01*
X640282Y-258959D01*
X640662Y-258459D01*
X640789Y-257792D01*
Y-254459D01*
G01X645889Y-259459D02*
X643355D01*
Y-254459D01*
X645889D01*
G01X644875Y-256876D02*
X643355D01*
G01X651115Y-254876D02*
X650735Y-254626D01*
X650292Y-254459D01*
X649785D01*
X649215Y-254709D01*
X648772Y-255126D01*
X648455Y-255626D01*
X648202Y-256459D01*
X648139Y-257209D01*
X648265Y-257959D01*
X648455Y-258459D01*
X648835Y-258959D01*
X649279Y-259292D01*
X649722Y-259459D01*
X650165D01*
X650609Y-259292D01*
X650989Y-259042D01*
X651305Y-258709D01*
G01X654822Y-254459D02*
Y-259459D01*
G01X653365Y-254459D02*
X656279D01*
G01X659922Y-259626D02*
X659795Y-259542D01*
Y-259376D01*
X659922Y-259292D01*
X660049Y-259376D01*
Y-259542D01*
X659922Y-259626D01*
G01Y-257376D02*
X659795Y-257292D01*
Y-257126D01*
X659922Y-257042D01*
X660049Y-257126D01*
Y-257292D01*
X659922Y-257376D01*
G01X617322Y-274459D02*
X817322D01*
G01X734955Y-301959D02*
Y-306959D01*
X737489D01*
G01X740562Y-301959D02*
X742082D01*
G01X741322D02*
Y-306959D01*
G01X740562D02*
X742082D01*
G01X746929Y-304292D02*
X747182Y-304042D01*
X747372Y-303626D01*
X747499Y-303042D01*
X747372Y-302542D01*
X747119Y-302209D01*
X746675Y-301959D01*
X744965D01*
Y-306959D01*
X747055D01*
X747499Y-306626D01*
X747752Y-306126D01*
X747879Y-305542D01*
X747752Y-304959D01*
X747372Y-304459D01*
X746929Y-304292D01*
X744965D01*
G01X751522Y-307126D02*
X751395Y-307042D01*
Y-306876D01*
X751522Y-306792D01*
X751649Y-306876D01*
Y-307042D01*
X751522Y-307126D01*
G01Y-304876D02*
X751395Y-304792D01*
Y-304626D01*
X751522Y-304542D01*
X751649Y-304626D01*
Y-304792D01*
X751522Y-304876D01*
G01X732322Y-299459D02*
Y-324459D01*
G01X779222Y-301959D02*
Y-306959D01*
G01X777765Y-301959D02*
X780679D01*
G01X784322Y-306959D02*
X783942Y-306876D01*
X783562Y-306542D01*
X783309Y-305959D01*
X783182Y-305292D01*
X783309Y-304626D01*
X783562Y-304042D01*
X783942Y-303709D01*
X784322Y-303626D01*
X784702Y-303709D01*
X785082Y-304042D01*
X785335Y-304626D01*
X785399Y-305292D01*
X785335Y-305959D01*
X785082Y-306542D01*
X784702Y-306876D01*
X784322Y-306959D01*
G01X789422D02*
X789042Y-306876D01*
X788662Y-306542D01*
X788409Y-305959D01*
X788282Y-305292D01*
X788409Y-304626D01*
X788662Y-304042D01*
X789042Y-303709D01*
X789422Y-303626D01*
X789802Y-303709D01*
X790182Y-304042D01*
X790435Y-304626D01*
X790499Y-305292D01*
X790435Y-305959D01*
X790182Y-306542D01*
X789802Y-306876D01*
X789422Y-306959D01*
G01X794522D02*
Y-301959D01*
G01X799622Y-307126D02*
X799495Y-307042D01*
Y-306876D01*
X799622Y-306792D01*
X799749Y-306876D01*
Y-307042D01*
X799622Y-307126D01*
G01Y-304876D02*
X799495Y-304792D01*
Y-304626D01*
X799622Y-304542D01*
X799749Y-304626D01*
Y-304792D01*
X799622Y-304876D01*
G01X775322Y-299459D02*
Y-324459D01*
G01Y-274459D02*
Y-299459D01*
G01X777955Y-281959D02*
Y-276959D01*
X779539D01*
X780045Y-277209D01*
X780362Y-277542D01*
X780489Y-278209D01*
X780362Y-278876D01*
X779982Y-279292D01*
X779539Y-279542D01*
X777955D01*
G01X779539D02*
X780489Y-281959D01*
G01X785589D02*
X783055D01*
Y-276959D01*
X785589D01*
G01X784575Y-279376D02*
X783055D01*
G01X787839Y-276959D02*
X789422Y-281959D01*
X791005Y-276959D01*
G01X794522Y-282126D02*
X794395Y-282042D01*
Y-281876D01*
X794522Y-281792D01*
X794649Y-281876D01*
Y-282042D01*
X794522Y-282126D01*
G01Y-279876D02*
X794395Y-279792D01*
Y-279626D01*
X794522Y-279542D01*
X794649Y-279626D01*
Y-279792D01*
X794522Y-279876D01*
G01X798082Y-326159D02*
X798162Y-326084D01*
X798222Y-325959D01*
X798262Y-325784D01*
X798222Y-325634D01*
X798142Y-325534D01*
X798002Y-325459D01*
X797462D01*
Y-326959D01*
X798122D01*
X798262Y-326859D01*
X798342Y-326709D01*
X798382Y-326534D01*
X798342Y-326359D01*
X798222Y-326209D01*
X798082Y-326159D01*
X797462D01*
G01X799482Y-326959D02*
Y-325959D01*
G01Y-326134D02*
X799402Y-326034D01*
X799282Y-325984D01*
X799142Y-325959D01*
X799002Y-326009D01*
X798882Y-326109D01*
X798802Y-326259D01*
X798762Y-326459D01*
X798802Y-326659D01*
X798882Y-326809D01*
X799002Y-326909D01*
X799142Y-326959D01*
X799282Y-326934D01*
X799402Y-326859D01*
X799482Y-326759D01*
G01X800022Y-326784D02*
X800122Y-326884D01*
X800262Y-326959D01*
X800382D01*
X800502Y-326909D01*
X800582Y-326834D01*
X800622Y-326734D01*
X800602Y-326584D01*
X800522Y-326509D01*
X800162Y-326359D01*
X800082Y-326184D01*
X800122Y-326059D01*
X800202Y-325984D01*
X800322Y-325959D01*
X800442Y-325984D01*
X800562Y-326059D01*
G01X801222Y-326284D02*
X801862D01*
X801802Y-326109D01*
X801702Y-326009D01*
X801562Y-325959D01*
X801422Y-325984D01*
X801302Y-326059D01*
X801222Y-326234D01*
X801182Y-326384D01*
Y-326534D01*
X801222Y-326684D01*
X801322Y-326834D01*
X801442Y-326934D01*
X801582Y-326959D01*
X801722Y-326909D01*
X801862Y-326759D01*
G01X802362Y-326959D02*
Y-325459D01*
G01Y-326209D02*
X802462Y-326059D01*
X802582Y-325984D01*
X802702Y-325959D01*
X802882Y-326009D01*
X803002Y-326109D01*
X803082Y-326284D01*
Y-326484D01*
X803042Y-326684D01*
X802962Y-326834D01*
X802822Y-326934D01*
X802702Y-326959D01*
X802582Y-326934D01*
X802462Y-326859D01*
X802362Y-326734D01*
G01X803922Y-326959D02*
X803802Y-326934D01*
X803682Y-326834D01*
X803602Y-326659D01*
X803562Y-326459D01*
X803602Y-326259D01*
X803682Y-326084D01*
X803802Y-325984D01*
X803922Y-325959D01*
X804042Y-325984D01*
X804162Y-326084D01*
X804242Y-326259D01*
X804262Y-326459D01*
X804242Y-326659D01*
X804162Y-326834D01*
X804042Y-326934D01*
X803922Y-326959D01*
G01X805482D02*
Y-325959D01*
G01Y-326134D02*
X805402Y-326034D01*
X805282Y-325984D01*
X805142Y-325959D01*
X805002Y-326009D01*
X804882Y-326109D01*
X804802Y-326259D01*
X804762Y-326459D01*
X804802Y-326659D01*
X804882Y-326809D01*
X805002Y-326909D01*
X805142Y-326959D01*
X805282Y-326934D01*
X805402Y-326859D01*
X805482Y-326759D01*
G01X806042Y-326959D02*
Y-325959D01*
G01Y-326159D02*
X806142Y-326059D01*
X806242Y-325984D01*
X806382Y-325959D01*
X806482Y-325984D01*
X806602Y-326059D01*
G01X807882Y-325459D02*
Y-326959D01*
G01Y-326734D02*
X807802Y-326859D01*
X807682Y-326934D01*
X807542Y-326959D01*
X807382Y-326909D01*
X807262Y-326784D01*
X807182Y-326634D01*
X807162Y-326459D01*
X807182Y-326284D01*
X807262Y-326134D01*
X807382Y-326009D01*
X807542Y-325959D01*
X807682Y-325984D01*
X807782Y-326034D01*
X807882Y-326134D01*
G01X809522Y-326959D02*
Y-325459D01*
X810022D01*
X810182Y-325534D01*
X810282Y-325634D01*
X810322Y-325834D01*
X810282Y-326034D01*
X810162Y-326159D01*
X810022Y-326234D01*
X809522D01*
G01X810022D02*
X810322Y-326959D01*
G01X810822Y-326284D02*
X811462D01*
X811402Y-326109D01*
X811302Y-326009D01*
X811162Y-325959D01*
X811022Y-325984D01*
X810902Y-326059D01*
X810822Y-326234D01*
X810782Y-326384D01*
Y-326534D01*
X810822Y-326684D01*
X810922Y-326834D01*
X811042Y-326934D01*
X811182Y-326959D01*
X811322Y-326909D01*
X811462Y-326759D01*
G01X811962Y-325959D02*
X812322Y-326959D01*
X812682Y-325959D01*
G01X813522Y-327009D02*
X813482Y-326984D01*
Y-326934D01*
X813522Y-326909D01*
X813562Y-326934D01*
Y-326984D01*
X813522Y-327009D01*
G01X814682Y-326959D02*
X814722Y-326634D01*
X814782Y-326359D01*
X814862Y-326109D01*
X814962Y-325834D01*
X815122Y-325459D01*
X814322D01*
G01X816082Y-326159D02*
X816162Y-326084D01*
X816222Y-325959D01*
X816262Y-325784D01*
X816222Y-325634D01*
X816142Y-325534D01*
X816002Y-325459D01*
X815462D01*
Y-326959D01*
X816122D01*
X816262Y-326859D01*
X816342Y-326709D01*
X816382Y-326534D01*
X816342Y-326359D01*
X816222Y-326209D01*
X816082Y-326159D01*
X815462D01*
G01X-320500Y-470483D02*
Y2626000D01*
X2967000D01*
Y-470483D01*
X-320500D01*
G01X-73428Y50617D02*
X-70328D01*
Y49697D01*
X-70483Y49390D01*
X-70845Y49160D01*
X-71258Y49083D01*
X-71671Y49160D01*
X-71981Y49352D01*
X-72136Y49697D01*
Y50617D01*
G01X-73531Y47440D02*
X-70328Y46060D01*
G01X-73428Y44532D02*
X-70328D01*
X-73428Y42768D01*
X-70328D01*
G01X-73531Y40550D02*
X-73480Y40627D01*
X-73376D01*
X-73325Y40550D01*
X-73376Y40473D01*
X-73480D01*
X-73531Y40550D01*
G01X-72136D02*
X-72085Y40627D01*
X-71981D01*
X-71930Y40550D01*
X-71981Y40473D01*
X-72085D01*
X-72136Y40550D01*
G01X-73428Y38293D02*
X-70328D01*
Y37527D01*
X-70483Y37220D01*
X-70690Y36990D01*
X-71000Y36798D01*
X-71361Y36645D01*
X-71878Y36607D01*
X-72395Y36645D01*
X-72756Y36798D01*
X-73066Y36990D01*
X-73273Y37220D01*
X-73428Y37527D01*
Y38293D01*
G01Y35308D02*
X-70328Y34350D01*
X-73428Y33392D01*
G01X-72343Y33737D02*
Y34963D01*
G01X-70328Y31250D02*
X-70431Y31557D01*
X-70690Y31787D01*
X-71000Y31940D01*
X-71413Y32055D01*
X-71878Y32093D01*
X-72343Y32055D01*
X-72756Y31940D01*
X-73066Y31787D01*
X-73325Y31557D01*
X-73428Y31250D01*
X-73325Y30943D01*
X-73066Y30713D01*
X-72756Y30560D01*
X-72343Y30445D01*
X-71878Y30407D01*
X-71413Y30445D01*
X-71000Y30560D01*
X-70690Y30713D01*
X-70431Y30943D01*
X-70328Y31250D01*
G01X-73428Y28878D02*
X-70328D01*
Y27422D01*
G01X-71826Y27958D02*
Y28878D01*
G01X-70328Y25050D02*
X-70431Y25357D01*
X-70690Y25587D01*
X-71000Y25740D01*
X-71413Y25855D01*
X-71878Y25893D01*
X-72343Y25855D01*
X-72756Y25740D01*
X-73066Y25587D01*
X-73325Y25357D01*
X-73428Y25050D01*
X-73325Y24743D01*
X-73066Y24513D01*
X-72756Y24360D01*
X-72343Y24245D01*
X-71878Y24207D01*
X-71413Y24245D01*
X-71000Y24360D01*
X-70690Y24513D01*
X-70431Y24743D01*
X-70328Y25050D01*
G01Y21950D02*
X-73428D01*
G01X-70328Y22832D02*
Y21068D01*
G01X-73428Y19578D02*
X-70328D01*
Y18122D01*
G01X-71826Y18658D02*
Y19578D01*
G01X-71775Y15443D02*
X-71620Y15290D01*
X-71361Y15175D01*
X-71000Y15098D01*
X-70690Y15175D01*
X-70483Y15328D01*
X-70328Y15597D01*
Y16632D01*
X-73428D01*
Y15367D01*
X-73221Y15098D01*
X-72911Y14945D01*
X-72550Y14868D01*
X-72188Y14945D01*
X-71878Y15175D01*
X-71775Y15443D01*
Y16632D01*
G01X-72136Y13378D02*
X-71775Y13110D01*
X-71568Y12880D01*
X-71465Y12573D01*
X-71568Y12305D01*
X-71775Y12113D01*
X-72085Y11960D01*
X-72446Y11922D01*
X-72756Y11960D01*
X-73066Y12113D01*
X-73325Y12343D01*
X-73428Y12612D01*
X-73325Y12918D01*
X-73015Y13187D01*
X-72550Y13340D01*
X-72033Y13378D01*
X-71361Y13302D01*
X-71000Y13187D01*
X-70638Y12995D01*
X-70380Y12727D01*
X-70328Y12458D01*
X-70431Y12190D01*
X-70690Y11998D01*
G01X-73428Y10393D02*
X-70328D01*
Y9627D01*
X-70483Y9320D01*
X-70690Y9090D01*
X-71000Y8898D01*
X-71361Y8745D01*
X-71878Y8707D01*
X-72395Y8745D01*
X-72756Y8898D01*
X-73066Y9090D01*
X-73273Y9320D01*
X-73428Y9627D01*
Y10393D01*
G01X-70328Y6450D02*
X-70431Y6757D01*
X-70690Y6987D01*
X-71000Y7140D01*
X-71413Y7255D01*
X-71878Y7293D01*
X-72343Y7255D01*
X-72756Y7140D01*
X-73066Y6987D01*
X-73325Y6757D01*
X-73428Y6450D01*
X-73325Y6143D01*
X-73066Y5913D01*
X-72756Y5760D01*
X-72343Y5645D01*
X-71878Y5607D01*
X-71413Y5645D01*
X-71000Y5760D01*
X-70690Y5913D01*
X-70431Y6143D01*
X-70328Y6450D01*
G01X-72928Y653817D02*
X-69828D01*
Y652897D01*
X-69983Y652590D01*
X-70345Y652360D01*
X-70758Y652283D01*
X-71171Y652360D01*
X-71481Y652552D01*
X-71636Y652897D01*
Y653817D01*
G01X-73031Y650640D02*
X-69828Y649260D01*
G01X-72928Y647732D02*
X-69828D01*
X-72928Y645968D01*
X-69828D01*
G01X-73031Y643750D02*
X-72980Y643827D01*
X-72876D01*
X-72825Y643750D01*
X-72876Y643673D01*
X-72980D01*
X-73031Y643750D01*
G01X-71636D02*
X-71585Y643827D01*
X-71481D01*
X-71430Y643750D01*
X-71481Y643673D01*
X-71585D01*
X-71636Y643750D01*
G01X-72928Y641493D02*
X-69828D01*
Y640727D01*
X-69983Y640420D01*
X-70190Y640190D01*
X-70500Y639998D01*
X-70861Y639845D01*
X-71378Y639807D01*
X-71895Y639845D01*
X-72256Y639998D01*
X-72566Y640190D01*
X-72773Y640420D01*
X-72928Y640727D01*
Y641493D01*
G01Y638508D02*
X-69828Y637550D01*
X-72928Y636592D01*
G01X-71843Y636937D02*
Y638163D01*
G01X-69828Y634450D02*
X-69931Y634757D01*
X-70190Y634987D01*
X-70500Y635140D01*
X-70913Y635255D01*
X-71378Y635293D01*
X-71843Y635255D01*
X-72256Y635140D01*
X-72566Y634987D01*
X-72825Y634757D01*
X-72928Y634450D01*
X-72825Y634143D01*
X-72566Y633913D01*
X-72256Y633760D01*
X-71843Y633645D01*
X-71378Y633607D01*
X-70913Y633645D01*
X-70500Y633760D01*
X-70190Y633913D01*
X-69931Y634143D01*
X-69828Y634450D01*
G01X-72928Y632078D02*
X-69828D01*
Y630622D01*
G01X-71326Y631158D02*
Y632078D01*
G01X-69828Y628250D02*
X-69931Y628557D01*
X-70190Y628787D01*
X-70500Y628940D01*
X-70913Y629055D01*
X-71378Y629093D01*
X-71843Y629055D01*
X-72256Y628940D01*
X-72566Y628787D01*
X-72825Y628557D01*
X-72928Y628250D01*
X-72825Y627943D01*
X-72566Y627713D01*
X-72256Y627560D01*
X-71843Y627445D01*
X-71378Y627407D01*
X-70913Y627445D01*
X-70500Y627560D01*
X-70190Y627713D01*
X-69931Y627943D01*
X-69828Y628250D01*
G01Y625150D02*
X-72928D01*
G01X-69828Y626032D02*
Y624268D01*
G01X-72928Y622778D02*
X-69828D01*
Y621322D01*
G01X-71326Y621858D02*
Y622778D01*
G01X-71275Y618643D02*
X-71120Y618490D01*
X-70861Y618375D01*
X-70500Y618298D01*
X-70190Y618375D01*
X-69983Y618528D01*
X-69828Y618797D01*
Y619832D01*
X-72928D01*
Y618567D01*
X-72721Y618298D01*
X-72411Y618145D01*
X-72050Y618068D01*
X-71688Y618145D01*
X-71378Y618375D01*
X-71275Y618643D01*
Y619832D01*
G01X-71636Y616578D02*
X-71275Y616310D01*
X-71068Y616080D01*
X-70965Y615773D01*
X-71068Y615505D01*
X-71275Y615313D01*
X-71585Y615160D01*
X-71946Y615122D01*
X-72256Y615160D01*
X-72566Y615313D01*
X-72825Y615543D01*
X-72928Y615812D01*
X-72825Y616118D01*
X-72515Y616387D01*
X-72050Y616540D01*
X-71533Y616578D01*
X-70861Y616502D01*
X-70500Y616387D01*
X-70138Y616195D01*
X-69880Y615927D01*
X-69828Y615658D01*
X-69931Y615390D01*
X-70190Y615198D01*
G01X-72928Y613593D02*
X-69828D01*
Y612827D01*
X-69983Y612520D01*
X-70190Y612290D01*
X-70500Y612098D01*
X-70861Y611945D01*
X-71378Y611907D01*
X-71895Y611945D01*
X-72256Y612098D01*
X-72566Y612290D01*
X-72773Y612520D01*
X-72928Y612827D01*
Y613593D01*
G01X-69828Y609650D02*
X-69931Y609957D01*
X-70190Y610187D01*
X-70500Y610340D01*
X-70913Y610455D01*
X-71378Y610493D01*
X-71843Y610455D01*
X-72256Y610340D01*
X-72566Y610187D01*
X-72825Y609957D01*
X-72928Y609650D01*
X-72825Y609343D01*
X-72566Y609113D01*
X-72256Y608960D01*
X-71843Y608845D01*
X-71378Y608807D01*
X-70913Y608845D01*
X-70500Y608960D01*
X-70190Y609113D01*
X-69931Y609343D01*
X-69828Y609650D01*
G01X-45318Y1147216D02*
X-71544D01*
X-58431Y1181792D01*
X-45318Y1147216D01*
G01X-40735Y845087D02*
X-40543Y844777D01*
X-40313Y844570D01*
X-40045Y844467D01*
X-39738Y844570D01*
X-39508Y844777D01*
X-39278Y845087D01*
X-39201Y845500D01*
Y847567D01*
G01X-36868Y844467D02*
X-36600Y844519D01*
X-36293Y844674D01*
X-36101Y844932D01*
X-36025Y845294D01*
X-36101Y845655D01*
X-36331Y845965D01*
X-36676Y846120D01*
X-37060D01*
X-37290Y846224D01*
X-37481Y846482D01*
X-37558Y846844D01*
X-37443Y847205D01*
X-37175Y847464D01*
X-36868Y847567D01*
X-36561Y847464D01*
X-36293Y847205D01*
X-36178Y846844D01*
X-36255Y846482D01*
X-36446Y846224D01*
X-36676Y846120D01*
X-37060D01*
X-37405Y845965D01*
X-37635Y845655D01*
X-37711Y845294D01*
X-37635Y844932D01*
X-37443Y844674D01*
X-37136Y844519D01*
X-36868Y844467D01*
G01X-33768D02*
Y847567D01*
X-34228Y846947D01*
G01Y844467D02*
X-33308D01*
G01X-40431Y842784D02*
X-14205D01*
X-27318Y808208D01*
X-40431Y842784D01*
G01X-53117Y1143620D02*
X-52925Y1143310D01*
X-52695Y1143103D01*
X-52427Y1143000D01*
X-52120Y1143103D01*
X-51890Y1143310D01*
X-51660Y1143620D01*
X-51583Y1144033D01*
Y1146100D01*
G01X-49250Y1143000D02*
X-48982Y1143052D01*
X-48675Y1143207D01*
X-48483Y1143465D01*
X-48407Y1143827D01*
X-48483Y1144188D01*
X-48713Y1144498D01*
X-49058Y1144653D01*
X-49442D01*
X-49672Y1144757D01*
X-49863Y1145015D01*
X-49940Y1145377D01*
X-49825Y1145738D01*
X-49557Y1145997D01*
X-49250Y1146100D01*
X-48943Y1145997D01*
X-48675Y1145738D01*
X-48560Y1145377D01*
X-48637Y1145015D01*
X-48828Y1144757D01*
X-49058Y1144653D01*
X-49442D01*
X-49787Y1144498D01*
X-50017Y1144188D01*
X-50093Y1143827D01*
X-50017Y1143465D01*
X-49825Y1143207D01*
X-49518Y1143052D01*
X-49250Y1143000D01*
G01X-46993Y1143620D02*
X-46763Y1143258D01*
X-46457Y1143052D01*
X-46112Y1143000D01*
X-45805Y1143052D01*
X-45498Y1143310D01*
X-45307Y1143620D01*
X-45268Y1143930D01*
X-45345Y1144292D01*
X-45613Y1144550D01*
X-45882Y1144653D01*
X-46227D01*
G01X-45882D02*
X-45652Y1144808D01*
X-45460Y1145067D01*
X-45383Y1145377D01*
X-45460Y1145687D01*
X-45652Y1145945D01*
X-45997Y1146100D01*
X-46342Y1146048D01*
X-46687Y1145842D01*
G01X7900Y125600D02*
X14100D01*
Y122400D01*
X7900D01*
Y125600D01*
G01X10500Y144031D02*
Y137831D01*
X7300D01*
Y144031D01*
X10500D01*
G01X19500Y499500D02*
Y493500D01*
X7500D01*
Y499500D01*
X19500D01*
G01X7900Y735600D02*
X14100D01*
Y732400D01*
X7900D01*
Y735600D01*
G01Y749600D02*
X14100D01*
Y746400D01*
X7900D01*
Y749600D01*
G01Y742600D02*
X14100D01*
Y739400D01*
X7900D01*
Y742600D01*
G01X5890Y1226087D02*
X8112D01*
X8577Y1226240D01*
X8887Y1226547D01*
X8990Y1226930D01*
X8887Y1227313D01*
X8577Y1227620D01*
X8112Y1227773D01*
X5890D01*
G01X8990Y1230490D02*
X5890D01*
X8112Y1229072D01*
Y1230988D01*
G01X8990Y1233130D02*
X5890D01*
X6510Y1232670D01*
G01X8990D02*
Y1233590D01*
G01X6407Y1235502D02*
X6097Y1235732D01*
X5942Y1236000D01*
X5890Y1236307D01*
X5993Y1236690D01*
X6252Y1236958D01*
X6562Y1237035D01*
X6872Y1236997D01*
X7130Y1236843D01*
X7647Y1236077D01*
X8008Y1235732D01*
X8525Y1235502D01*
X8990Y1235425D01*
Y1237035D01*
G01X20400Y125600D02*
X26600D01*
Y122400D01*
X20400D01*
Y125600D01*
G01X11700Y147031D02*
X17700D01*
Y135031D01*
X11700D01*
Y147031D01*
G01X19631Y150231D02*
Y134462D01*
X55969D01*
X60969Y139462D01*
Y150231D01*
G01X55969Y175800D02*
X19631D01*
Y160031D01*
G01X31100Y253900D02*
X24900D01*
Y257100D01*
X31100D01*
Y253900D01*
G01X31191Y270328D02*
X37391D01*
Y267128D01*
X31191D01*
Y270328D01*
G01X23891Y261128D02*
X17691D01*
Y264328D01*
X23891D01*
Y261128D01*
G01X27100Y249900D02*
X20900D01*
Y253100D01*
X27100D01*
Y249900D01*
G01X24900Y261100D02*
X31100D01*
Y257900D01*
X24900D01*
Y261100D01*
G01X37391Y262128D02*
X31191D01*
Y265328D01*
X37391D01*
Y262128D01*
G01X11191Y262628D02*
Y268828D01*
X14391D01*
Y262628D01*
X11191D01*
G01X24100Y260100D02*
Y253900D01*
X20900D01*
Y260100D01*
X24100D01*
G01X28533Y319100D02*
Y326600D01*
X30773D01*
X31520Y326225D01*
X32080Y325350D01*
X32267Y324350D01*
X32080Y323350D01*
X31613Y322600D01*
X30773Y322225D01*
X28533D01*
G01X36220Y318850D02*
X39580Y326600D01*
G01X43253Y319100D02*
Y326600D01*
X47547Y319100D01*
Y326600D01*
G01X52900Y318850D02*
X52713Y318975D01*
Y319225D01*
X52900Y319350D01*
X53087Y319225D01*
Y318975D01*
X52900Y318850D01*
G01Y322225D02*
X52713Y322350D01*
Y322600D01*
X52900Y322725D01*
X53087Y322600D01*
Y322350D01*
X52900Y322225D01*
G01X58347Y319100D02*
Y326600D01*
X60213D01*
X60960Y326225D01*
X61520Y325725D01*
X61987Y324975D01*
X62360Y324100D01*
X62453Y322850D01*
X62360Y321600D01*
X61987Y320725D01*
X61520Y319975D01*
X60960Y319475D01*
X60213Y319100D01*
X58347D01*
G01X65567D02*
X67900Y326600D01*
X70233Y319100D01*
G01X69393Y321725D02*
X66407D01*
G01X75400Y326600D02*
X74653Y326350D01*
X74093Y325725D01*
X73720Y324975D01*
X73440Y323975D01*
X73347Y322850D01*
X73440Y321725D01*
X73720Y320725D01*
X74093Y319975D01*
X74653Y319350D01*
X75400Y319100D01*
X76147Y319350D01*
X76707Y319975D01*
X77080Y320725D01*
X77360Y321725D01*
X77453Y322850D01*
X77360Y323975D01*
X77080Y324975D01*
X76707Y325725D01*
X76147Y326350D01*
X75400Y326600D01*
G01X81127Y319100D02*
Y326600D01*
X84673D01*
G01X83367Y322975D02*
X81127D01*
G01X90400Y326600D02*
X89653Y326350D01*
X89093Y325725D01*
X88720Y324975D01*
X88440Y323975D01*
X88347Y322850D01*
X88440Y321725D01*
X88720Y320725D01*
X89093Y319975D01*
X89653Y319350D01*
X90400Y319100D01*
X91147Y319350D01*
X91707Y319975D01*
X92080Y320725D01*
X92360Y321725D01*
X92453Y322850D01*
X92360Y323975D01*
X92080Y324975D01*
X91707Y325725D01*
X91147Y326350D01*
X90400Y326600D01*
G01X97900D02*
Y319100D01*
G01X95753Y326600D02*
X100047D01*
G01X103627Y319100D02*
Y326600D01*
X107173D01*
G01X105867Y322975D02*
X103627D01*
G01X113647Y323100D02*
X114020Y323475D01*
X114300Y324100D01*
X114487Y324975D01*
X114300Y325725D01*
X113927Y326225D01*
X113273Y326600D01*
X110753D01*
Y319100D01*
X113833D01*
X114487Y319600D01*
X114860Y320350D01*
X115047Y321225D01*
X114860Y322100D01*
X114300Y322850D01*
X113647Y323100D01*
X110753D01*
G01X118627Y322225D02*
X119280Y323100D01*
X119840Y323600D01*
X120587Y323850D01*
X121240Y323600D01*
X121707Y323100D01*
X122080Y322350D01*
X122173Y321475D01*
X122080Y320725D01*
X121707Y319975D01*
X121147Y319350D01*
X120493Y319100D01*
X119747Y319350D01*
X119093Y320100D01*
X118720Y321225D01*
X118627Y322475D01*
X118813Y324100D01*
X119093Y324975D01*
X119560Y325850D01*
X120213Y326475D01*
X120867Y326600D01*
X121520Y326350D01*
X121987Y325725D01*
G01X125847Y319100D02*
Y326600D01*
X127713D01*
X128460Y326225D01*
X129020Y325725D01*
X129487Y324975D01*
X129860Y324100D01*
X129953Y322850D01*
X129860Y321600D01*
X129487Y320725D01*
X129020Y319975D01*
X128460Y319475D01*
X127713Y319100D01*
X125847D01*
G01X135400Y326600D02*
X134653Y326350D01*
X134093Y325725D01*
X133720Y324975D01*
X133440Y323975D01*
X133347Y322850D01*
X133440Y321725D01*
X133720Y320725D01*
X134093Y319975D01*
X134653Y319350D01*
X135400Y319100D01*
X136147Y319350D01*
X136707Y319975D01*
X137080Y320725D01*
X137360Y321725D01*
X137453Y322850D01*
X137360Y323975D01*
X137080Y324975D01*
X136707Y325725D01*
X136147Y326350D01*
X135400Y326600D01*
G01X26500Y390000D02*
Y377000D01*
X11500D01*
Y390000D01*
X26500D01*
G01X11900Y394600D02*
X18100D01*
Y391400D01*
X11900D01*
Y394600D01*
G01X20110Y391400D02*
X19803Y391452D01*
X19535Y391658D01*
X19305Y391968D01*
X19152Y392330D01*
X19075Y392743D01*
Y393157D01*
X19152Y393570D01*
X19305Y393932D01*
X19535Y394242D01*
X19803Y394448D01*
X20110Y394500D01*
X20417Y394448D01*
X20685Y394242D01*
X20915Y393932D01*
X21068Y393570D01*
X21145Y393157D01*
Y392743D01*
X21068Y392330D01*
X20915Y391968D01*
X20685Y391658D01*
X20417Y391452D01*
X20110Y391400D01*
G01X20417Y392227D02*
X20877Y391400D01*
G01X23210D02*
Y394500D01*
X22750Y393880D01*
G01Y391400D02*
X23670D01*
G01X26770D02*
Y394500D01*
X25352Y392278D01*
X27268D01*
G01X11900Y503600D02*
X18100D01*
Y500400D01*
X11900D01*
Y503600D01*
G01X10400Y488600D02*
X16600D01*
Y485400D01*
X10400D01*
Y488600D01*
G01X22900D02*
X29100D01*
Y485400D01*
X22900D01*
Y488600D01*
G01X26667Y501610D02*
Y499388D01*
X26820Y498923D01*
X27127Y498613D01*
X27510Y498510D01*
X27893Y498613D01*
X28200Y498923D01*
X28353Y499388D01*
Y501610D01*
G01X31070Y498510D02*
Y501610D01*
X29652Y499388D01*
X31568D01*
G01X33710Y501610D02*
X33403Y501507D01*
X33173Y501248D01*
X33020Y500938D01*
X32905Y500525D01*
X32867Y500060D01*
X32905Y499595D01*
X33020Y499182D01*
X33173Y498872D01*
X33403Y498613D01*
X33710Y498510D01*
X34017Y498613D01*
X34247Y498872D01*
X34400Y499182D01*
X34515Y499595D01*
X34553Y500060D01*
X34515Y500525D01*
X34400Y500938D01*
X34247Y501248D01*
X34017Y501507D01*
X33710Y501610D01*
G01X37270Y498510D02*
Y501610D01*
X35852Y499388D01*
X37768D01*
G01X16600Y489400D02*
X10400D01*
Y492600D01*
X16600D01*
Y489400D01*
G01X11900Y512600D02*
X18100D01*
Y509400D01*
X11900D01*
Y512600D01*
G01Y517100D02*
X18100D01*
Y513900D01*
X11900D01*
Y517100D01*
G01Y508100D02*
X18100D01*
Y504900D01*
X11900D01*
Y508100D01*
G01Y521600D02*
X18100D01*
Y518400D01*
X11900D01*
Y521600D01*
G01X24540Y525440D02*
Y527940D01*
X24220Y527440D01*
G01Y525440D02*
X24860D01*
G01X26740D02*
X26927Y525482D01*
X27140Y525607D01*
X27273Y525815D01*
X27327Y526107D01*
X27273Y526398D01*
X27113Y526648D01*
X26873Y526773D01*
X26607D01*
X26447Y526857D01*
X26313Y527065D01*
X26260Y527357D01*
X26340Y527648D01*
X26527Y527857D01*
X26740Y527940D01*
X26953Y527857D01*
X27140Y527648D01*
X27220Y527357D01*
X27167Y527065D01*
X27033Y526857D01*
X26873Y526773D01*
X26607D01*
X26367Y526648D01*
X26207Y526398D01*
X26153Y526107D01*
X26207Y525815D01*
X26340Y525607D01*
X26553Y525482D01*
X26740Y525440D01*
G01X22030Y520980D02*
X19530D01*
X20030Y520660D01*
G01X22030D02*
Y521300D01*
G01X21738Y522727D02*
X21947Y522913D01*
X22030Y523127D01*
X21947Y523340D01*
X21697Y523527D01*
X21322Y523660D01*
X20947Y523713D01*
X20488D01*
X20113Y523660D01*
X19780Y523527D01*
X19613Y523367D01*
X19530Y523180D01*
X19613Y522967D01*
X19780Y522807D01*
X20030Y522700D01*
X20363Y522647D01*
X20655Y522700D01*
X20947Y522833D01*
X21113Y522993D01*
X21155Y523180D01*
X21072Y523393D01*
X20863Y523553D01*
X20488Y523713D01*
G01X20457Y508873D02*
X20207Y509033D01*
X20082Y509220D01*
X20040Y509433D01*
X20123Y509700D01*
X20332Y509887D01*
X20582Y509940D01*
X20832Y509913D01*
X21040Y509807D01*
X21457Y509273D01*
X21748Y509033D01*
X22165Y508873D01*
X22540Y508820D01*
Y509940D01*
G01Y511900D02*
X20040D01*
X21832Y510913D01*
Y512247D01*
G01X19100Y519500D02*
X23100D01*
G01X27500Y508626D02*
X25626D01*
Y510500D01*
G01Y522500D02*
Y524374D01*
G01D02*
X27500D01*
G01X28600Y535600D02*
Y529400D01*
X25400D01*
Y535600D01*
X28600D01*
G01X34600D02*
Y529400D01*
X31400D01*
Y535600D01*
X34600D01*
G01X20600D02*
Y529400D01*
X17400D01*
Y535600D01*
X20600D01*
G01X24600D02*
Y529400D01*
X21400D01*
Y535600D01*
X24600D01*
G01X22400Y642600D02*
X28600D01*
Y639400D01*
X22400D01*
Y642600D01*
G01X19600Y639400D02*
X13400D01*
Y642600D01*
X19600D01*
Y639400D01*
G01X29400Y642307D02*
X31622D01*
X32087Y642460D01*
X32397Y642767D01*
X32500Y643150D01*
X32397Y643533D01*
X32087Y643840D01*
X31622Y643993D01*
X29400D01*
G01X29917Y645522D02*
X29607Y645752D01*
X29452Y646020D01*
X29400Y646327D01*
X29503Y646710D01*
X29762Y646978D01*
X30072Y647055D01*
X30382Y647017D01*
X30640Y646863D01*
X31157Y646097D01*
X31518Y645752D01*
X32035Y645522D01*
X32500Y645445D01*
Y647055D01*
G01X31880Y648507D02*
X32242Y648737D01*
X32448Y649043D01*
X32500Y649388D01*
X32448Y649695D01*
X32190Y650002D01*
X31880Y650193D01*
X31570Y650232D01*
X31208Y650155D01*
X30950Y649887D01*
X30847Y649618D01*
Y649273D01*
G01Y649618D02*
X30692Y649848D01*
X30433Y650040D01*
X30123Y650117D01*
X29813Y650040D01*
X29555Y649848D01*
X29400Y649503D01*
X29452Y649158D01*
X29658Y648813D01*
G01X29400Y653307D02*
X31622D01*
X32087Y653460D01*
X32397Y653767D01*
X32500Y654150D01*
X32397Y654533D01*
X32087Y654840D01*
X31622Y654993D01*
X29400D01*
G01X29917Y656522D02*
X29607Y656752D01*
X29452Y657020D01*
X29400Y657327D01*
X29503Y657710D01*
X29762Y657978D01*
X30072Y658055D01*
X30382Y658017D01*
X30640Y657863D01*
X31157Y657097D01*
X31518Y656752D01*
X32035Y656522D01*
X32500Y656445D01*
Y658055D01*
G01Y660810D02*
X29400D01*
X31622Y659392D01*
Y661308D01*
G01X19600Y658400D02*
X13400D01*
Y661600D01*
X19600D01*
Y658400D01*
G01Y652400D02*
X13400D01*
Y655600D01*
X19600D01*
Y652400D01*
G01X22400Y647100D02*
X28600D01*
Y643900D01*
X22400D01*
Y647100D01*
G01Y661600D02*
X28600D01*
Y658400D01*
X22400D01*
Y661600D01*
G01Y655600D02*
X28600D01*
Y652400D01*
X22400D01*
Y655600D01*
G01X19600Y643900D02*
X13400D01*
Y647100D01*
X19600D01*
Y643900D01*
G01X29400Y665807D02*
X31622D01*
X32087Y665960D01*
X32397Y666267D01*
X32500Y666650D01*
X32397Y667033D01*
X32087Y667340D01*
X31622Y667493D01*
X29400D01*
G01X29917Y669022D02*
X29607Y669252D01*
X29452Y669520D01*
X29400Y669827D01*
X29503Y670210D01*
X29762Y670478D01*
X30072Y670555D01*
X30382Y670517D01*
X30640Y670363D01*
X31157Y669597D01*
X31518Y669252D01*
X32035Y669022D01*
X32500Y668945D01*
Y670555D01*
G01X32035Y672007D02*
X32293Y672237D01*
X32448Y672505D01*
X32500Y672850D01*
X32397Y673195D01*
X32190Y673463D01*
X31828Y673655D01*
X31415Y673693D01*
X31002Y673617D01*
X30743Y673425D01*
X30537Y673157D01*
X30485Y672888D01*
X30537Y672620D01*
X30743Y672275D01*
X29400Y672390D01*
Y673425D01*
G01Y678307D02*
X31622D01*
X32087Y678460D01*
X32397Y678767D01*
X32500Y679150D01*
X32397Y679533D01*
X32087Y679840D01*
X31622Y679993D01*
X29400D01*
G01X29917Y681522D02*
X29607Y681752D01*
X29452Y682020D01*
X29400Y682327D01*
X29503Y682710D01*
X29762Y682978D01*
X30072Y683055D01*
X30382Y683017D01*
X30640Y682863D01*
X31157Y682097D01*
X31518Y681752D01*
X32035Y681522D01*
X32500Y681445D01*
Y683055D01*
G01X31208Y684622D02*
X30847Y684890D01*
X30640Y685120D01*
X30537Y685427D01*
X30640Y685695D01*
X30847Y685887D01*
X31157Y686040D01*
X31518Y686078D01*
X31828Y686040D01*
X32138Y685887D01*
X32397Y685657D01*
X32500Y685388D01*
X32397Y685082D01*
X32087Y684813D01*
X31622Y684660D01*
X31105Y684622D01*
X30433Y684698D01*
X30072Y684813D01*
X29710Y685005D01*
X29452Y685273D01*
X29400Y685542D01*
X29503Y685810D01*
X29762Y686002D01*
G01X19600Y684400D02*
X13400D01*
Y687600D01*
X19600D01*
Y684400D01*
G01Y678900D02*
X13400D01*
Y682100D01*
X19600D01*
Y678900D01*
G01X22400Y687600D02*
X28600D01*
Y684400D01*
X22400D01*
Y687600D01*
G01Y682100D02*
X28600D01*
Y678900D01*
X22400D01*
Y682100D01*
G01Y674100D02*
X28600D01*
Y670900D01*
X22400D01*
Y674100D01*
G01Y668100D02*
X28600D01*
Y664900D01*
X22400D01*
Y668100D01*
G01X19600Y670900D02*
X13400D01*
Y674100D01*
X19600D01*
Y670900D01*
G01Y664900D02*
X13400D01*
Y668100D01*
X19600D01*
Y664900D01*
G01X18400Y735600D02*
X24600D01*
Y732400D01*
X18400D01*
Y735600D01*
G01X18100Y713400D02*
X11900D01*
Y716600D01*
X18100D01*
Y713400D01*
G01X11900Y724600D02*
X18100D01*
Y721400D01*
X11900D01*
Y724600D01*
G01Y720600D02*
X18100D01*
Y717400D01*
X11900D01*
Y720600D01*
G01X18100Y725400D02*
X11900D01*
Y728600D01*
X18100D01*
Y725400D01*
G01X18400Y749600D02*
X24600D01*
Y746400D01*
X18400D01*
Y749600D01*
G01Y742600D02*
X24600D01*
Y739400D01*
X18400D01*
Y742600D01*
G01X15600Y869500D02*
X21600D01*
Y857500D01*
X15600D01*
Y869500D01*
G01X24383Y855000D02*
Y858100D01*
X25303D01*
X25610Y857945D01*
X25840Y857583D01*
X25917Y857170D01*
X25840Y856757D01*
X25648Y856447D01*
X25303Y856292D01*
X24383D01*
G01X29093Y857842D02*
X28863Y857997D01*
X28595Y858100D01*
X28288D01*
X27943Y857945D01*
X27675Y857687D01*
X27483Y857377D01*
X27330Y856860D01*
X27292Y856395D01*
X27368Y855930D01*
X27483Y855620D01*
X27713Y855310D01*
X27982Y855103D01*
X28250Y855000D01*
X28518D01*
X28787Y855103D01*
X29017Y855258D01*
X29208Y855465D01*
G01X31810Y855000D02*
Y858100D01*
X30392Y855878D01*
X32308D01*
G01X34450Y855000D02*
X34718Y855052D01*
X35025Y855207D01*
X35217Y855465D01*
X35293Y855827D01*
X35217Y856188D01*
X34987Y856498D01*
X34642Y856653D01*
X34258D01*
X34028Y856757D01*
X33837Y857015D01*
X33760Y857377D01*
X33875Y857738D01*
X34143Y857997D01*
X34450Y858100D01*
X34757Y857997D01*
X35025Y857738D01*
X35140Y857377D01*
X35063Y857015D01*
X34872Y856757D01*
X34642Y856653D01*
X34258D01*
X33913Y856498D01*
X33683Y856188D01*
X33607Y855827D01*
X33683Y855465D01*
X33875Y855207D01*
X34182Y855052D01*
X34450Y855000D01*
G01X24331Y875100D02*
Y859331D01*
X60669D01*
X65669Y864331D01*
Y875100D01*
G01X12200Y867600D02*
Y861400D01*
X9000D01*
Y867600D01*
X12200D01*
G01X60669Y900669D02*
X24331D01*
Y884900D01*
G01X24600Y972900D02*
X18400D01*
Y976100D01*
X24600D01*
Y972900D01*
G01X20400Y983100D02*
X26600D01*
Y979900D01*
X20400D01*
Y983100D01*
G01Y987100D02*
X26600D01*
Y983900D01*
X20400D01*
Y987100D01*
G01X19100Y985600D02*
Y979400D01*
X15900D01*
Y985600D01*
X19100D01*
G01X31191Y997100D02*
X37391D01*
Y993900D01*
X31191D01*
Y997100D01*
G01X18600Y994100D02*
Y987900D01*
X15400D01*
Y994100D01*
X18600D01*
G01X11191Y989400D02*
Y995600D01*
X14391D01*
Y989400D01*
X11191D01*
G01X37391Y988900D02*
X31191D01*
Y992100D01*
X37391D01*
Y988900D01*
G01X9500Y1218000D02*
Y1224000D01*
X21500D01*
Y1218000D01*
X9500D01*
G01X38000Y1217500D02*
X25000D01*
Y1232500D01*
X38000D01*
Y1217500D01*
G01X12400Y1216600D02*
X18600D01*
Y1213400D01*
X12400D01*
Y1216600D01*
G01X19831Y1236257D02*
X11169D01*
Y1225743D01*
X19831D01*
Y1236257D01*
G01X18600Y1237900D02*
X12400D01*
Y1241100D01*
X18600D01*
Y1237900D01*
G01X31400Y1237100D02*
X37600D01*
Y1233900D01*
X31400D01*
Y1237100D01*
G01X29450Y1307000D02*
G03I-9450J0D01*
G01X15845Y1317500D02*
Y1320600D01*
G01X17455D02*
Y1317500D01*
G01Y1319050D02*
X15845D01*
G01X19750Y1317500D02*
Y1320600D01*
X19290Y1319980D01*
G01Y1317500D02*
X20210D01*
G01X22007Y1317965D02*
X22237Y1317707D01*
X22505Y1317552D01*
X22850Y1317500D01*
X23195Y1317603D01*
X23463Y1317810D01*
X23655Y1318172D01*
X23693Y1318585D01*
X23617Y1318998D01*
X23425Y1319257D01*
X23157Y1319463D01*
X22888Y1319515D01*
X22620Y1319463D01*
X22275Y1319257D01*
X22390Y1320600D01*
X23425D01*
G01X53450Y17500D02*
G03I-9450J0D01*
G01X40259Y29252D02*
Y32352D01*
G01X41869D02*
Y29252D01*
G01Y30802D02*
X40259D01*
G01X44164Y29252D02*
Y32352D01*
X43704Y31732D01*
G01Y29252D02*
X44624D01*
G01X46421Y29872D02*
X46651Y29510D01*
X46957Y29304D01*
X47302Y29252D01*
X47609Y29304D01*
X47916Y29562D01*
X48107Y29872D01*
X48146Y30182D01*
X48069Y30544D01*
X47801Y30802D01*
X47532Y30905D01*
X47187D01*
G01X47532D02*
X47762Y31060D01*
X47954Y31319D01*
X48031Y31629D01*
X47954Y31939D01*
X47762Y32197D01*
X47417Y32352D01*
X47072Y32300D01*
X46727Y32094D01*
G01X51413Y66500D02*
X48987D01*
G01X40307Y58500D02*
Y61600D01*
X41073D01*
X41380Y61445D01*
X41610Y61238D01*
X41802Y60928D01*
X41955Y60567D01*
X41993Y60050D01*
X41955Y59533D01*
X41802Y59172D01*
X41610Y58862D01*
X41380Y58655D01*
X41073Y58500D01*
X40307D01*
G01X44250D02*
Y61600D01*
X43790Y60980D01*
G01Y58500D02*
X44710D01*
G01X47350D02*
Y61600D01*
X46890Y60980D01*
G01Y58500D02*
X47810D01*
G01X49607Y59120D02*
X49837Y58758D01*
X50143Y58552D01*
X50488Y58500D01*
X50795Y58552D01*
X51102Y58810D01*
X51293Y59120D01*
X51332Y59430D01*
X51255Y59792D01*
X50987Y60050D01*
X50718Y60153D01*
X50373D01*
G01X50718D02*
X50948Y60308D01*
X51140Y60567D01*
X51217Y60877D01*
X51140Y61187D01*
X50948Y61445D01*
X50603Y61600D01*
X50258Y61548D01*
X49913Y61342D01*
G01X67043Y61042D02*
X52543D01*
Y66642D01*
X67043D01*
Y61042D01*
G01X54043Y61142D02*
Y66542D01*
G01X53543D02*
Y61142D01*
G01X53043D02*
Y66542D01*
G01X59143Y54742D02*
X52943D01*
Y57942D01*
X59143D01*
Y54742D01*
G01X40807Y90100D02*
Y87878D01*
X40960Y87413D01*
X41267Y87103D01*
X41650Y87000D01*
X42033Y87103D01*
X42340Y87413D01*
X42493Y87878D01*
Y90100D01*
G01X43907Y87620D02*
X44137Y87258D01*
X44443Y87052D01*
X44788Y87000D01*
X45095Y87052D01*
X45402Y87310D01*
X45593Y87620D01*
X45632Y87930D01*
X45555Y88292D01*
X45287Y88550D01*
X45018Y88653D01*
X44673D01*
G01X45018D02*
X45248Y88808D01*
X45440Y89067D01*
X45517Y89377D01*
X45440Y89687D01*
X45248Y89945D01*
X44903Y90100D01*
X44558Y90048D01*
X44213Y89842D01*
G01X48310Y87000D02*
Y90100D01*
X46892Y87878D01*
X48808D01*
G01X50222Y89583D02*
X50452Y89893D01*
X50720Y90048D01*
X51027Y90100D01*
X51410Y89997D01*
X51678Y89738D01*
X51755Y89428D01*
X51717Y89118D01*
X51563Y88860D01*
X50797Y88343D01*
X50452Y87982D01*
X50222Y87465D01*
X50145Y87000D01*
X51755D01*
G01X53087Y70500D02*
X55513D01*
G01X37713Y67500D02*
Y70000D01*
X38247D01*
X38460Y69875D01*
X38620Y69708D01*
X38753Y69458D01*
X38860Y69167D01*
X38887Y68750D01*
X38860Y68333D01*
X38753Y68042D01*
X38620Y67792D01*
X38460Y67625D01*
X38247Y67500D01*
X37713D01*
G01X39993Y69583D02*
X40153Y69833D01*
X40340Y69958D01*
X40553Y70000D01*
X40820Y69917D01*
X41007Y69708D01*
X41060Y69458D01*
X41033Y69208D01*
X40927Y69000D01*
X40393Y68583D01*
X40153Y68292D01*
X39993Y67875D01*
X39940Y67500D01*
X41060D01*
G01X43020D02*
Y70000D01*
X42033Y68208D01*
X43367D01*
G01X44393Y69583D02*
X44553Y69833D01*
X44740Y69958D01*
X44953Y70000D01*
X45220Y69917D01*
X45407Y69708D01*
X45460Y69458D01*
X45433Y69208D01*
X45327Y69000D01*
X44793Y68583D01*
X44553Y68292D01*
X44393Y67875D01*
X44340Y67500D01*
X45460D01*
G01X53443Y76942D02*
X59643D01*
Y73742D01*
X53443D01*
Y76942D01*
G01X59600Y78092D02*
X53400D01*
Y81292D01*
X59600D01*
Y78092D01*
G01X53400Y85792D02*
X59600D01*
Y82592D01*
X53400D01*
Y85792D01*
G01X51087Y100500D02*
X53513D01*
G01X40807Y92000D02*
Y95100D01*
X41573D01*
X41880Y94945D01*
X42110Y94738D01*
X42302Y94428D01*
X42455Y94067D01*
X42493Y93550D01*
X42455Y93033D01*
X42302Y92672D01*
X42110Y92362D01*
X41880Y92155D01*
X41573Y92000D01*
X40807D01*
G01X44022Y94583D02*
X44252Y94893D01*
X44520Y95048D01*
X44827Y95100D01*
X45210Y94997D01*
X45478Y94738D01*
X45555Y94428D01*
X45517Y94118D01*
X45363Y93860D01*
X44597Y93343D01*
X44252Y92982D01*
X44022Y92465D01*
X43945Y92000D01*
X45555D01*
G01X47007Y92620D02*
X47237Y92258D01*
X47543Y92052D01*
X47888Y92000D01*
X48195Y92052D01*
X48502Y92310D01*
X48693Y92620D01*
X48732Y92930D01*
X48655Y93292D01*
X48387Y93550D01*
X48118Y93653D01*
X47773D01*
G01X48118D02*
X48348Y93808D01*
X48540Y94067D01*
X48617Y94377D01*
X48540Y94687D01*
X48348Y94945D01*
X48003Y95100D01*
X47658Y95048D01*
X47313Y94842D01*
G01X50298Y92362D02*
X50567Y92103D01*
X50873Y92000D01*
X51180Y92103D01*
X51448Y92413D01*
X51640Y92878D01*
X51717Y93343D01*
Y93912D01*
X51640Y94377D01*
X51448Y94790D01*
X51218Y94997D01*
X50950Y95100D01*
X50643Y94997D01*
X50413Y94790D01*
X50260Y94480D01*
X50183Y94067D01*
X50260Y93705D01*
X50452Y93343D01*
X50682Y93137D01*
X50950Y93085D01*
X51257Y93188D01*
X51487Y93447D01*
X51717Y93912D01*
G01X53280Y99272D02*
Y95728D01*
X60366D01*
Y99272D01*
X53358D01*
G01X53573Y96400D02*
X53673Y99100D01*
Y96000D01*
G01X55413Y124500D02*
X52987D01*
G01X37507Y118950D02*
Y122050D01*
X38273D01*
X38580Y121895D01*
X38810Y121688D01*
X39002Y121378D01*
X39155Y121017D01*
X39193Y120500D01*
X39155Y119983D01*
X39002Y119622D01*
X38810Y119312D01*
X38580Y119105D01*
X38273Y118950D01*
X37507D01*
G01X41450D02*
Y122050D01*
X40990Y121430D01*
G01Y118950D02*
X41910D01*
G01X44550D02*
Y122050D01*
X44090Y121430D01*
G01Y118950D02*
X45010D01*
G01X48110D02*
Y122050D01*
X46692Y119828D01*
X48608D01*
G01X67543Y117542D02*
X53900D01*
G01X54543Y117642D02*
Y123042D01*
G01X54043D02*
Y117642D01*
G01X53543D02*
Y123042D01*
G01X53700Y123142D02*
X67543D01*
Y117542D01*
G01X52845Y126908D02*
X55271D01*
G01X37507Y125450D02*
Y128550D01*
X38273D01*
X38580Y128395D01*
X38810Y128188D01*
X39002Y127878D01*
X39155Y127517D01*
X39193Y127000D01*
X39155Y126483D01*
X39002Y126122D01*
X38810Y125812D01*
X38580Y125605D01*
X38273Y125450D01*
X37507D01*
G01X40722Y128033D02*
X40952Y128343D01*
X41220Y128498D01*
X41527Y128550D01*
X41910Y128447D01*
X42178Y128188D01*
X42255Y127878D01*
X42217Y127568D01*
X42063Y127310D01*
X41297Y126793D01*
X40952Y126432D01*
X40722Y125915D01*
X40645Y125450D01*
X42255D01*
G01X45010D02*
Y128550D01*
X43592Y126328D01*
X45508D01*
G01X47650Y125450D02*
Y128550D01*
X47190Y127930D01*
G01Y125450D02*
X48110D01*
G01X50087Y116500D02*
X52513D01*
G01X37507Y111950D02*
Y115050D01*
X38273D01*
X38580Y114895D01*
X38810Y114688D01*
X39002Y114378D01*
X39155Y114017D01*
X39193Y113500D01*
X39155Y112983D01*
X39002Y112622D01*
X38810Y112312D01*
X38580Y112105D01*
X38273Y111950D01*
X37507D01*
G01X40722Y114533D02*
X40952Y114843D01*
X41220Y114998D01*
X41527Y115050D01*
X41910Y114947D01*
X42178Y114688D01*
X42255Y114378D01*
X42217Y114068D01*
X42063Y113810D01*
X41297Y113293D01*
X40952Y112932D01*
X40722Y112415D01*
X40645Y111950D01*
X42255D01*
G01X45010D02*
Y115050D01*
X43592Y112828D01*
X45508D01*
G01X47650Y115050D02*
X47343Y114947D01*
X47113Y114688D01*
X46960Y114378D01*
X46845Y113965D01*
X46807Y113500D01*
X46845Y113035D01*
X46960Y112622D01*
X47113Y112312D01*
X47343Y112053D01*
X47650Y111950D01*
X47957Y112053D01*
X48187Y112312D01*
X48340Y112622D01*
X48455Y113035D01*
X48493Y113500D01*
X48455Y113965D01*
X48340Y114378D01*
X48187Y114688D01*
X47957Y114947D01*
X47650Y115050D01*
G01X53280Y115464D02*
Y111920D01*
X60366D01*
Y115464D01*
X53358D01*
G01X53573Y112592D02*
X53673Y115292D01*
Y112192D01*
G01X50139Y130131D02*
Y133231D01*
X51059D01*
X51366Y133076D01*
X51596Y132714D01*
X51673Y132301D01*
X51596Y131888D01*
X51404Y131578D01*
X51059Y131423D01*
X50139D01*
G01X54849Y132973D02*
X54619Y133128D01*
X54351Y133231D01*
X54044D01*
X53699Y133076D01*
X53431Y132818D01*
X53239Y132508D01*
X53086Y131991D01*
X53048Y131526D01*
X53124Y131061D01*
X53239Y130751D01*
X53469Y130441D01*
X53738Y130234D01*
X54006Y130131D01*
X54274D01*
X54543Y130234D01*
X54773Y130389D01*
X54964Y130596D01*
G01X56378Y132714D02*
X56608Y133024D01*
X56876Y133179D01*
X57183Y133231D01*
X57566Y133128D01*
X57834Y132869D01*
X57911Y132559D01*
X57873Y132249D01*
X57719Y131991D01*
X56953Y131474D01*
X56608Y131113D01*
X56378Y130596D01*
X56301Y130131D01*
X57911D01*
G01X59478Y132714D02*
X59708Y133024D01*
X59976Y133179D01*
X60283Y133231D01*
X60666Y133128D01*
X60934Y132869D01*
X61011Y132559D01*
X60973Y132249D01*
X60819Y131991D01*
X60053Y131474D01*
X59708Y131113D01*
X59478Y130596D01*
X59401Y130131D01*
X61011D01*
G01X43900Y287900D02*
Y294100D01*
X47100D01*
Y287900D01*
X43900D01*
G01X48161Y276128D02*
X41961D01*
Y279328D01*
X48161D01*
Y276128D01*
G01X47900Y294600D02*
X54100D01*
Y291400D01*
X47900D01*
Y294600D01*
G01X54100Y287400D02*
X47900D01*
Y290600D01*
X54100D01*
Y287400D01*
G01X41961Y284328D02*
X48161D01*
Y281128D01*
X41961D01*
Y284328D01*
G01X42883Y333500D02*
Y336600D01*
X43803D01*
X44110Y336445D01*
X44340Y336083D01*
X44417Y335670D01*
X44340Y335257D01*
X44148Y334947D01*
X43803Y334792D01*
X42883D01*
G01X47593Y336342D02*
X47363Y336497D01*
X47095Y336600D01*
X46788D01*
X46443Y336445D01*
X46175Y336187D01*
X45983Y335877D01*
X45830Y335360D01*
X45792Y334895D01*
X45868Y334430D01*
X45983Y334120D01*
X46213Y333810D01*
X46482Y333603D01*
X46750Y333500D01*
X47018D01*
X47287Y333603D01*
X47517Y333758D01*
X47708Y333965D01*
G01X50310Y333500D02*
Y336600D01*
X48892Y334378D01*
X50808D01*
G01X52222Y336083D02*
X52452Y336393D01*
X52720Y336548D01*
X53027Y336600D01*
X53410Y336497D01*
X53678Y336238D01*
X53755Y335928D01*
X53717Y335618D01*
X53563Y335360D01*
X52797Y334843D01*
X52452Y334482D01*
X52222Y333965D01*
X52145Y333500D01*
X53755D01*
G01X42874Y353400D02*
Y342631D01*
X47874Y337631D01*
G01D02*
X84212D01*
Y353400D01*
G01Y363200D02*
Y378969D01*
X47874D01*
X42874Y373969D01*
Y363200D01*
G01X52257Y383669D02*
Y392331D01*
X41743D01*
Y383669D01*
X52257D01*
G01X53900Y384900D02*
Y391100D01*
X57100D01*
Y384900D01*
X53900D01*
G01X34700Y382400D02*
Y392600D01*
X39300D01*
Y382400D01*
X34700D01*
G01X54413Y405000D02*
X51987D01*
G01X39807Y406000D02*
Y409100D01*
X40573D01*
X40880Y408945D01*
X41110Y408738D01*
X41302Y408428D01*
X41455Y408067D01*
X41493Y407550D01*
X41455Y407033D01*
X41302Y406672D01*
X41110Y406362D01*
X40880Y406155D01*
X40573Y406000D01*
X39807D01*
G01X43750D02*
Y409100D01*
X43290Y408480D01*
G01Y406000D02*
X44210D01*
G01X46007Y406620D02*
X46237Y406258D01*
X46543Y406052D01*
X46888Y406000D01*
X47195Y406052D01*
X47502Y406310D01*
X47693Y406620D01*
X47732Y406930D01*
X47655Y407292D01*
X47387Y407550D01*
X47118Y407653D01*
X46773D01*
G01X47118D02*
X47348Y407808D01*
X47540Y408067D01*
X47617Y408377D01*
X47540Y408687D01*
X47348Y408945D01*
X47003Y409100D01*
X46658Y409048D01*
X46313Y408842D01*
G01X50410Y406000D02*
Y409100D01*
X48992Y406878D01*
X50908D01*
G01X53043Y406178D02*
Y411578D01*
G01X53543D02*
Y406178D01*
G01X54043D02*
Y411578D01*
G01X67043Y406078D02*
X52543D01*
Y411678D01*
X67043D01*
Y406078D01*
G01X42677Y396890D02*
Y394668D01*
X42830Y394203D01*
X43137Y393893D01*
X43520Y393790D01*
X43903Y393893D01*
X44210Y394203D01*
X44363Y394668D01*
Y396890D01*
G01X47080Y393790D02*
Y396890D01*
X45662Y394668D01*
X47578D01*
G01X49720Y393790D02*
Y396890D01*
X49260Y396270D01*
G01Y393790D02*
X50180D01*
G01X52820Y396890D02*
X52513Y396787D01*
X52283Y396528D01*
X52130Y396218D01*
X52015Y395805D01*
X51977Y395340D01*
X52015Y394875D01*
X52130Y394462D01*
X52283Y394152D01*
X52513Y393893D01*
X52820Y393790D01*
X53127Y393893D01*
X53357Y394152D01*
X53510Y394462D01*
X53625Y394875D01*
X53663Y395340D01*
X53625Y395805D01*
X53510Y396218D01*
X53357Y396528D01*
X53127Y396787D01*
X52820Y396890D01*
G01X39807Y410500D02*
Y413600D01*
X40573D01*
X40880Y413445D01*
X41110Y413238D01*
X41302Y412928D01*
X41455Y412567D01*
X41493Y412050D01*
X41455Y411533D01*
X41302Y411172D01*
X41110Y410862D01*
X40880Y410655D01*
X40573Y410500D01*
X39807D01*
G01X43022Y413083D02*
X43252Y413393D01*
X43520Y413548D01*
X43827Y413600D01*
X44210Y413497D01*
X44478Y413238D01*
X44555Y412928D01*
X44517Y412618D01*
X44363Y412360D01*
X43597Y411843D01*
X43252Y411482D01*
X43022Y410965D01*
X42945Y410500D01*
X44555D01*
G01X47310D02*
Y413600D01*
X45892Y411378D01*
X47808D01*
G01X49950Y410500D02*
X50218Y410552D01*
X50525Y410707D01*
X50717Y410965D01*
X50793Y411327D01*
X50717Y411688D01*
X50487Y411998D01*
X50142Y412153D01*
X49758D01*
X49528Y412257D01*
X49337Y412515D01*
X49260Y412877D01*
X49375Y413238D01*
X49643Y413497D01*
X49950Y413600D01*
X50257Y413497D01*
X50525Y413238D01*
X50640Y412877D01*
X50563Y412515D01*
X50372Y412257D01*
X50142Y412153D01*
X49758D01*
X49413Y411998D01*
X49183Y411688D01*
X49107Y411327D01*
X49183Y410965D01*
X49375Y410707D01*
X49682Y410552D01*
X49950Y410500D01*
G01X59143Y399778D02*
X52943D01*
Y402978D01*
X59143D01*
Y399778D01*
G01X53087Y415500D02*
X55513D01*
G01X53400Y430828D02*
X59600D01*
Y427628D01*
X53400D01*
Y430828D01*
G01X59600Y423128D02*
X53400D01*
Y426328D01*
X59600D01*
Y423128D01*
G01X53443Y421978D02*
X59643D01*
Y418778D01*
X53443D01*
Y421978D01*
G01X51087Y441000D02*
X53513D01*
G01X40307Y442500D02*
Y445600D01*
X41073D01*
X41380Y445445D01*
X41610Y445238D01*
X41802Y444928D01*
X41955Y444567D01*
X41993Y444050D01*
X41955Y443533D01*
X41802Y443172D01*
X41610Y442862D01*
X41380Y442655D01*
X41073Y442500D01*
X40307D01*
G01X43522Y445083D02*
X43752Y445393D01*
X44020Y445548D01*
X44327Y445600D01*
X44710Y445497D01*
X44978Y445238D01*
X45055Y444928D01*
X45017Y444618D01*
X44863Y444360D01*
X44097Y443843D01*
X43752Y443482D01*
X43522Y442965D01*
X43445Y442500D01*
X45055D01*
G01X47810D02*
Y445600D01*
X46392Y443378D01*
X48308D01*
G01X49607Y442965D02*
X49837Y442707D01*
X50105Y442552D01*
X50450Y442500D01*
X50795Y442603D01*
X51063Y442810D01*
X51255Y443172D01*
X51293Y443585D01*
X51217Y443998D01*
X51025Y444257D01*
X50757Y444463D01*
X50488Y444515D01*
X50220Y444463D01*
X49875Y444257D01*
X49990Y445600D01*
X51025D01*
G01X53073Y442628D02*
X53173Y445328D01*
Y442228D01*
G01X52780Y445500D02*
Y441956D01*
X59866D01*
Y445500D01*
X52858D01*
G01X49087Y454500D02*
X51513D01*
G01X53073Y456128D02*
X53173Y458828D01*
Y455728D01*
G01X52780Y459000D02*
Y455456D01*
X59866D01*
Y459000D01*
X52858D01*
G01X54913Y468000D02*
X52487D01*
G01X39307Y470500D02*
Y473600D01*
X40073D01*
X40380Y473445D01*
X40610Y473238D01*
X40802Y472928D01*
X40955Y472567D01*
X40993Y472050D01*
X40955Y471533D01*
X40802Y471172D01*
X40610Y470862D01*
X40380Y470655D01*
X40073Y470500D01*
X39307D01*
G01X43250D02*
Y473600D01*
X42790Y472980D01*
G01Y470500D02*
X43710D01*
G01X45507Y471120D02*
X45737Y470758D01*
X46043Y470552D01*
X46388Y470500D01*
X46695Y470552D01*
X47002Y470810D01*
X47193Y471120D01*
X47232Y471430D01*
X47155Y471792D01*
X46887Y472050D01*
X46618Y472153D01*
X46273D01*
G01X46618D02*
X46848Y472308D01*
X47040Y472567D01*
X47117Y472877D01*
X47040Y473187D01*
X46848Y473445D01*
X46503Y473600D01*
X46158Y473548D01*
X45813Y473342D01*
G01X48722Y471792D02*
X48990Y472153D01*
X49220Y472360D01*
X49527Y472463D01*
X49795Y472360D01*
X49987Y472153D01*
X50140Y471843D01*
X50178Y471482D01*
X50140Y471172D01*
X49987Y470862D01*
X49757Y470603D01*
X49488Y470500D01*
X49182Y470603D01*
X48913Y470913D01*
X48760Y471378D01*
X48722Y471895D01*
X48798Y472567D01*
X48913Y472928D01*
X49105Y473290D01*
X49373Y473548D01*
X49642Y473600D01*
X49910Y473497D01*
X50102Y473238D01*
G01X53043Y461178D02*
Y466578D01*
G01X53543D02*
Y461178D01*
G01X54043D02*
Y466578D01*
G01X67043Y461078D02*
X52543D01*
Y466678D01*
X67043D01*
Y461078D01*
G01X39307Y466000D02*
Y469100D01*
X40073D01*
X40380Y468945D01*
X40610Y468738D01*
X40802Y468428D01*
X40955Y468067D01*
X40993Y467550D01*
X40955Y467033D01*
X40802Y466672D01*
X40610Y466362D01*
X40380Y466155D01*
X40073Y466000D01*
X39307D01*
G01X42522Y468583D02*
X42752Y468893D01*
X43020Y469048D01*
X43327Y469100D01*
X43710Y468997D01*
X43978Y468738D01*
X44055Y468428D01*
X44017Y468118D01*
X43863Y467860D01*
X43097Y467343D01*
X42752Y466982D01*
X42522Y466465D01*
X42445Y466000D01*
X44055D01*
G01X46810D02*
Y469100D01*
X45392Y466878D01*
X47308D01*
G01X48722Y467292D02*
X48990Y467653D01*
X49220Y467860D01*
X49527Y467963D01*
X49795Y467860D01*
X49987Y467653D01*
X50140Y467343D01*
X50178Y466982D01*
X50140Y466672D01*
X49987Y466362D01*
X49757Y466103D01*
X49488Y466000D01*
X49182Y466103D01*
X48913Y466413D01*
X48760Y466878D01*
X48722Y467395D01*
X48798Y468067D01*
X48913Y468428D01*
X49105Y468790D01*
X49373Y469048D01*
X49642Y469100D01*
X49910Y468997D01*
X50102Y468738D01*
G01X52587Y470500D02*
X55013D01*
G01X39307Y475000D02*
Y478100D01*
X40073D01*
X40380Y477945D01*
X40610Y477738D01*
X40802Y477428D01*
X40955Y477067D01*
X40993Y476550D01*
X40955Y476033D01*
X40802Y475672D01*
X40610Y475362D01*
X40380Y475155D01*
X40073Y475000D01*
X39307D01*
G01X42522Y477583D02*
X42752Y477893D01*
X43020Y478048D01*
X43327Y478100D01*
X43710Y477997D01*
X43978Y477738D01*
X44055Y477428D01*
X44017Y477118D01*
X43863Y476860D01*
X43097Y476343D01*
X42752Y475982D01*
X42522Y475465D01*
X42445Y475000D01*
X44055D01*
G01X46810D02*
Y478100D01*
X45392Y475878D01*
X47308D01*
G01X49373Y475000D02*
X49450Y475672D01*
X49565Y476240D01*
X49718Y476757D01*
X49910Y477325D01*
X50217Y478100D01*
X48683D01*
G01X58525Y478900D02*
X52325D01*
Y482100D01*
X58525D01*
Y478900D01*
G01X58450Y498900D02*
X52250D01*
Y502100D01*
X58450D01*
Y498900D01*
G01Y493900D02*
X52250D01*
Y497100D01*
X58450D01*
Y493900D01*
G01Y488900D02*
X52250D01*
Y492100D01*
X58450D01*
Y488900D01*
G01Y483900D02*
X52250D01*
Y487100D01*
X58450D01*
Y483900D01*
G01Y524400D02*
X52250D01*
Y527600D01*
X58450D01*
Y524400D01*
G01Y519400D02*
X52250D01*
Y522600D01*
X58450D01*
Y519400D01*
G01Y514400D02*
X52250D01*
Y517600D01*
X58450D01*
Y514400D01*
G01Y509400D02*
X52250D01*
Y512600D01*
X58450D01*
Y509400D01*
G01Y504400D02*
X52250D01*
Y507600D01*
X58450D01*
Y504400D01*
G01X46550Y521600D02*
X44050D01*
X44550Y521280D01*
G01X46550D02*
Y521920D01*
G01X44467Y523293D02*
X44217Y523453D01*
X44092Y523640D01*
X44050Y523853D01*
X44133Y524120D01*
X44342Y524307D01*
X44592Y524360D01*
X44842Y524333D01*
X45050Y524227D01*
X45467Y523693D01*
X45758Y523453D01*
X46175Y523293D01*
X46550Y523240D01*
Y524360D01*
G01X46900Y509867D02*
X46358Y509920D01*
X45900Y510000D01*
X45483Y510107D01*
X45025Y510240D01*
X44400Y510453D01*
Y509387D01*
G01X39093Y504592D02*
X39280Y504883D01*
X39440Y505050D01*
X39653Y505133D01*
X39840Y505050D01*
X39973Y504883D01*
X40080Y504633D01*
X40107Y504342D01*
X40080Y504092D01*
X39973Y503842D01*
X39813Y503633D01*
X39627Y503550D01*
X39413Y503633D01*
X39227Y503883D01*
X39120Y504258D01*
X39093Y504675D01*
X39147Y505217D01*
X39227Y505508D01*
X39360Y505800D01*
X39547Y506008D01*
X39733Y506050D01*
X39920Y505967D01*
X40053Y505758D01*
G01X36500Y506100D02*
Y504100D01*
G01X43900Y517500D02*
X47900D01*
G01X41374Y510500D02*
Y508626D01*
X39500D01*
G01Y524374D02*
X41374D01*
Y522500D01*
G01X58525Y534400D02*
X52325D01*
Y537600D01*
X58525D01*
Y534400D01*
G01X58450Y529400D02*
X52250D01*
Y532600D01*
X58450D01*
Y529400D01*
G01X38400Y527250D02*
Y529750D01*
X38080Y529250D01*
G01Y527250D02*
X38720D01*
G01X40013Y527750D02*
X40173Y527458D01*
X40387Y527292D01*
X40627Y527250D01*
X40840Y527292D01*
X41053Y527500D01*
X41187Y527750D01*
X41213Y528000D01*
X41160Y528292D01*
X40973Y528500D01*
X40787Y528583D01*
X40547D01*
G01X40787D02*
X40947Y528708D01*
X41080Y528917D01*
X41133Y529167D01*
X41080Y529417D01*
X40947Y529625D01*
X40707Y529750D01*
X40467Y529708D01*
X40227Y529542D01*
G01X34500Y528900D02*
Y526900D01*
G01X40845Y551500D02*
Y554600D01*
G01X42455D02*
Y551500D01*
G01Y553050D02*
X40845D01*
G01X43907Y552120D02*
X44137Y551758D01*
X44443Y551552D01*
X44788Y551500D01*
X45095Y551552D01*
X45402Y551810D01*
X45593Y552120D01*
X45632Y552430D01*
X45555Y552792D01*
X45287Y553050D01*
X45018Y553153D01*
X44673D01*
G01X45018D02*
X45248Y553308D01*
X45440Y553567D01*
X45517Y553877D01*
X45440Y554187D01*
X45248Y554445D01*
X44903Y554600D01*
X44558Y554548D01*
X44213Y554342D01*
G01X55600Y639400D02*
X49400D01*
Y642600D01*
X55600D01*
Y639400D01*
G01X33700Y641669D02*
Y650331D01*
X44300D01*
Y641669D01*
X41638D01*
X39000Y644500D01*
X36362Y641669D01*
X33700D01*
G01Y652669D02*
Y661331D01*
X44300D01*
Y652669D01*
X41638D01*
X39000Y655500D01*
X36362Y652669D01*
X33700D01*
G01X55600Y658400D02*
X49400D01*
Y661600D01*
X55600D01*
Y658400D01*
G01Y652400D02*
X49400D01*
Y655600D01*
X55600D01*
Y652400D01*
G01Y645400D02*
X49400D01*
Y648600D01*
X55600D01*
Y645400D01*
G01X33700Y665169D02*
Y673831D01*
X44300D01*
Y665169D01*
X41638D01*
X39000Y668000D01*
X36362Y665169D01*
X33700D01*
G01Y677669D02*
Y686331D01*
X44300D01*
Y677669D01*
X41638D01*
X39000Y680500D01*
X36362Y677669D01*
X33700D01*
G01X55600Y683400D02*
X49400D01*
Y686600D01*
X55600D01*
Y683400D01*
G01Y677400D02*
X49400D01*
Y680600D01*
X55600D01*
Y677400D01*
G01Y670900D02*
X49400D01*
Y674100D01*
X55600D01*
Y670900D01*
G01Y664900D02*
X49400D01*
Y668100D01*
X55600D01*
Y664900D01*
G01X44307Y691600D02*
Y689378D01*
X44460Y688913D01*
X44767Y688603D01*
X45150Y688500D01*
X45533Y688603D01*
X45840Y688913D01*
X45993Y689378D01*
Y691600D01*
G01X48173Y688500D02*
X48250Y689172D01*
X48365Y689740D01*
X48518Y690257D01*
X48710Y690825D01*
X49017Y691600D01*
X47483D01*
G01X48400Y724100D02*
Y692900D01*
X32600D01*
Y724100D01*
X38200D01*
X40500Y721800D01*
X42800Y724100D01*
X48400D01*
G01X40307Y732100D02*
Y729878D01*
X40460Y729413D01*
X40767Y729103D01*
X41150Y729000D01*
X41533Y729103D01*
X41840Y729413D01*
X41993Y729878D01*
Y732100D01*
G01X43407Y729465D02*
X43637Y729207D01*
X43905Y729052D01*
X44250Y729000D01*
X44595Y729103D01*
X44863Y729310D01*
X45055Y729672D01*
X45093Y730085D01*
X45017Y730498D01*
X44825Y730757D01*
X44557Y730963D01*
X44288Y731015D01*
X44020Y730963D01*
X43675Y730757D01*
X43790Y732100D01*
X44825D01*
G01X46698Y729362D02*
X46967Y729103D01*
X47273Y729000D01*
X47580Y729103D01*
X47848Y729413D01*
X48040Y729878D01*
X48117Y730343D01*
Y730912D01*
X48040Y731377D01*
X47848Y731790D01*
X47618Y731997D01*
X47350Y732100D01*
X47043Y731997D01*
X46813Y731790D01*
X46660Y731480D01*
X46583Y731067D01*
X46660Y730705D01*
X46852Y730343D01*
X47082Y730137D01*
X47350Y730085D01*
X47657Y730188D01*
X47887Y730447D01*
X48117Y730912D01*
G01X46100Y752900D02*
X42300D01*
X40500Y751100D01*
X38700Y752900D01*
X34900D01*
Y733100D01*
X46100D01*
Y752900D01*
G01X39100Y725900D02*
X32900D01*
Y729100D01*
X39100D01*
Y725900D01*
G01X56913Y768000D02*
X54487D01*
G01X39807Y767000D02*
Y770100D01*
X40573D01*
X40880Y769945D01*
X41110Y769738D01*
X41302Y769428D01*
X41455Y769067D01*
X41493Y768550D01*
X41455Y768033D01*
X41302Y767672D01*
X41110Y767362D01*
X40880Y767155D01*
X40573Y767000D01*
X39807D01*
G01X43750D02*
Y770100D01*
X43290Y769480D01*
G01Y767000D02*
X44210D01*
G01X46007Y767620D02*
X46237Y767258D01*
X46543Y767052D01*
X46888Y767000D01*
X47195Y767052D01*
X47502Y767310D01*
X47693Y767620D01*
X47732Y767930D01*
X47655Y768292D01*
X47387Y768550D01*
X47118Y768653D01*
X46773D01*
G01X47118D02*
X47348Y768808D01*
X47540Y769067D01*
X47617Y769377D01*
X47540Y769687D01*
X47348Y769945D01*
X47003Y770100D01*
X46658Y770048D01*
X46313Y769842D01*
G01X49950Y767000D02*
X50218Y767052D01*
X50525Y767207D01*
X50717Y767465D01*
X50793Y767827D01*
X50717Y768188D01*
X50487Y768498D01*
X50142Y768653D01*
X49758D01*
X49528Y768757D01*
X49337Y769015D01*
X49260Y769377D01*
X49375Y769738D01*
X49643Y769997D01*
X49950Y770100D01*
X50257Y769997D01*
X50525Y769738D01*
X50640Y769377D01*
X50563Y769015D01*
X50372Y768757D01*
X50142Y768653D01*
X49758D01*
X49413Y768498D01*
X49183Y768188D01*
X49107Y767827D01*
X49183Y767465D01*
X49375Y767207D01*
X49682Y767052D01*
X49950Y767000D01*
G01X53043Y769564D02*
Y774964D01*
G01X53543D02*
Y769564D01*
G01X54043D02*
Y774964D01*
G01X67043Y769464D02*
X52543D01*
Y775064D01*
X67043D01*
Y769464D01*
G01X49544Y778236D02*
X51970D01*
G01X40313Y777600D02*
Y780100D01*
X40847D01*
X41060Y779975D01*
X41220Y779808D01*
X41353Y779558D01*
X41460Y779267D01*
X41487Y778850D01*
X41460Y778433D01*
X41353Y778142D01*
X41220Y777892D01*
X41060Y777725D01*
X40847Y777600D01*
X40313D01*
G01X42593Y779683D02*
X42753Y779933D01*
X42940Y780058D01*
X43153Y780100D01*
X43420Y780017D01*
X43607Y779808D01*
X43660Y779558D01*
X43633Y779308D01*
X43527Y779100D01*
X42993Y778683D01*
X42753Y778392D01*
X42593Y777975D01*
X42540Y777600D01*
X43660D01*
G01X44713Y777975D02*
X44873Y777767D01*
X45060Y777642D01*
X45300Y777600D01*
X45540Y777683D01*
X45727Y777850D01*
X45860Y778142D01*
X45887Y778475D01*
X45833Y778808D01*
X45700Y779017D01*
X45513Y779183D01*
X45327Y779225D01*
X45140Y779183D01*
X44900Y779017D01*
X44980Y780100D01*
X45700D01*
G01X47820Y777600D02*
Y780100D01*
X46833Y778308D01*
X48167D01*
G01X53573Y777400D02*
X53673Y780100D01*
Y777000D01*
G01X53280Y780272D02*
Y776728D01*
X60366D01*
Y780272D01*
X53358D01*
G01X59143Y763164D02*
X52943D01*
Y766364D01*
X59143D01*
Y763164D01*
G01X53400Y794214D02*
X59600D01*
Y791014D01*
X53400D01*
Y794214D01*
G01X59600Y786514D02*
X53400D01*
Y789714D01*
X59600D01*
Y786514D01*
G01X53443Y785364D02*
X59643D01*
Y782164D01*
X53443D01*
Y785364D01*
G01X51900Y796400D02*
Y802600D01*
X55100D01*
Y796400D01*
X51900D01*
G01X37807Y825500D02*
Y828600D01*
X38573D01*
X38880Y828445D01*
X39110Y828238D01*
X39302Y827928D01*
X39455Y827567D01*
X39493Y827050D01*
X39455Y826533D01*
X39302Y826172D01*
X39110Y825862D01*
X38880Y825655D01*
X38573Y825500D01*
X37807D01*
G01X41750D02*
Y828600D01*
X41290Y827980D01*
G01Y825500D02*
X42210D01*
G01X45310D02*
Y828600D01*
X43892Y826378D01*
X45808D01*
G01X47950Y828600D02*
X47643Y828497D01*
X47413Y828238D01*
X47260Y827928D01*
X47145Y827515D01*
X47107Y827050D01*
X47145Y826585D01*
X47260Y826172D01*
X47413Y825862D01*
X47643Y825603D01*
X47950Y825500D01*
X48257Y825603D01*
X48487Y825862D01*
X48640Y826172D01*
X48755Y826585D01*
X48793Y827050D01*
X48755Y827515D01*
X48640Y827928D01*
X48487Y828238D01*
X48257Y828497D01*
X47950Y828600D01*
G01X53543Y829964D02*
Y824564D01*
G01X54043D02*
Y829964D01*
G01X67043Y824464D02*
X53700D01*
G01X49087Y808500D02*
X51513D01*
G01X40807Y810500D02*
Y813600D01*
X41573D01*
X41880Y813445D01*
X42110Y813238D01*
X42302Y812928D01*
X42455Y812567D01*
X42493Y812050D01*
X42455Y811533D01*
X42302Y811172D01*
X42110Y810862D01*
X41880Y810655D01*
X41573Y810500D01*
X40807D01*
G01X44022Y813083D02*
X44252Y813393D01*
X44520Y813548D01*
X44827Y813600D01*
X45210Y813497D01*
X45478Y813238D01*
X45555Y812928D01*
X45517Y812618D01*
X45363Y812360D01*
X44597Y811843D01*
X44252Y811482D01*
X44022Y810965D01*
X43945Y810500D01*
X45555D01*
G01X47007Y810965D02*
X47237Y810707D01*
X47505Y810552D01*
X47850Y810500D01*
X48195Y810603D01*
X48463Y810810D01*
X48655Y811172D01*
X48693Y811585D01*
X48617Y811998D01*
X48425Y812257D01*
X48157Y812463D01*
X47888Y812515D01*
X47620Y812463D01*
X47275Y812257D01*
X47390Y813600D01*
X48425D01*
G01X50950Y810500D02*
Y813600D01*
X50490Y812980D01*
G01Y810500D02*
X51410D01*
G01X53073Y808900D02*
X53173Y811600D01*
Y808500D01*
G01X52780Y811772D02*
Y808228D01*
X59866D01*
Y811772D01*
X52858D01*
G01X49587Y820500D02*
X52013D01*
G01X40807Y815000D02*
Y818100D01*
X41573D01*
X41880Y817945D01*
X42110Y817738D01*
X42302Y817428D01*
X42455Y817067D01*
X42493Y816550D01*
X42455Y816033D01*
X42302Y815672D01*
X42110Y815362D01*
X41880Y815155D01*
X41573Y815000D01*
X40807D01*
G01X44022Y817583D02*
X44252Y817893D01*
X44520Y818048D01*
X44827Y818100D01*
X45210Y817997D01*
X45478Y817738D01*
X45555Y817428D01*
X45517Y817118D01*
X45363Y816860D01*
X44597Y816343D01*
X44252Y815982D01*
X44022Y815465D01*
X43945Y815000D01*
X45555D01*
G01X47007Y815465D02*
X47237Y815207D01*
X47505Y815052D01*
X47850Y815000D01*
X48195Y815103D01*
X48463Y815310D01*
X48655Y815672D01*
X48693Y816085D01*
X48617Y816498D01*
X48425Y816757D01*
X48157Y816963D01*
X47888Y817015D01*
X47620Y816963D01*
X47275Y816757D01*
X47390Y818100D01*
X48425D01*
G01X50222Y817583D02*
X50452Y817893D01*
X50720Y818048D01*
X51027Y818100D01*
X51410Y817997D01*
X51678Y817738D01*
X51755Y817428D01*
X51717Y817118D01*
X51563Y816860D01*
X50797Y816343D01*
X50452Y815982D01*
X50222Y815465D01*
X50145Y815000D01*
X51755D01*
G01X53073Y819514D02*
X53173Y822214D01*
Y819114D01*
G01X52780Y822386D02*
Y818842D01*
X59866D01*
Y822386D01*
X52858D01*
G01X59600Y803400D02*
X53400D01*
Y806600D01*
X59600D01*
Y803400D01*
G01Y814400D02*
X53400D01*
Y817600D01*
X59600D01*
Y814400D01*
G01X54913Y831500D02*
X52487D01*
G01X53700Y830064D02*
X67043D01*
Y824464D01*
G01X43807Y834000D02*
Y837100D01*
X44573D01*
X44880Y836945D01*
X45110Y836738D01*
X45302Y836428D01*
X45455Y836067D01*
X45493Y835550D01*
X45455Y835033D01*
X45302Y834672D01*
X45110Y834362D01*
X44880Y834155D01*
X44573Y834000D01*
X43807D01*
G01X47022Y836583D02*
X47252Y836893D01*
X47520Y837048D01*
X47827Y837100D01*
X48210Y836997D01*
X48478Y836738D01*
X48555Y836428D01*
X48517Y836118D01*
X48363Y835860D01*
X47597Y835343D01*
X47252Y834982D01*
X47022Y834465D01*
X46945Y834000D01*
X48555D01*
G01X50007Y834465D02*
X50237Y834207D01*
X50505Y834052D01*
X50850Y834000D01*
X51195Y834103D01*
X51463Y834310D01*
X51655Y834672D01*
X51693Y835085D01*
X51617Y835498D01*
X51425Y835757D01*
X51157Y835963D01*
X50888Y836015D01*
X50620Y835963D01*
X50275Y835757D01*
X50390Y837100D01*
X51425D01*
G01X53107Y834620D02*
X53337Y834258D01*
X53643Y834052D01*
X53988Y834000D01*
X54295Y834052D01*
X54602Y834310D01*
X54793Y834620D01*
X54832Y834930D01*
X54755Y835292D01*
X54487Y835550D01*
X54218Y835653D01*
X53873D01*
G01X54218D02*
X54448Y835808D01*
X54640Y836067D01*
X54717Y836377D01*
X54640Y836687D01*
X54448Y836945D01*
X54103Y837100D01*
X53758Y837048D01*
X53413Y836842D01*
G01X43650Y844000D02*
X43343Y844052D01*
X43075Y844258D01*
X42845Y844568D01*
X42692Y844930D01*
X42615Y845343D01*
Y845757D01*
X42692Y846170D01*
X42845Y846532D01*
X43075Y846842D01*
X43343Y847048D01*
X43650Y847100D01*
X43957Y847048D01*
X44225Y846842D01*
X44455Y846532D01*
X44608Y846170D01*
X44685Y845757D01*
Y845343D01*
X44608Y844930D01*
X44455Y844568D01*
X44225Y844258D01*
X43957Y844052D01*
X43650Y844000D01*
G01X43957Y844827D02*
X44417Y844000D01*
G01X46750D02*
Y847100D01*
X46290Y846480D01*
G01Y844000D02*
X47210D01*
G01X49007Y844465D02*
X49237Y844207D01*
X49505Y844052D01*
X49850Y844000D01*
X50195Y844103D01*
X50463Y844310D01*
X50655Y844672D01*
X50693Y845085D01*
X50617Y845498D01*
X50425Y845757D01*
X50157Y845963D01*
X49888Y846015D01*
X49620Y845963D01*
X49275Y845757D01*
X49390Y847100D01*
X50425D01*
G01X52500Y844000D02*
Y857000D01*
X67500D01*
Y844000D01*
X52500D01*
G01X48661Y1002900D02*
X42461D01*
Y1006100D01*
X48661D01*
Y1002900D01*
G01X42461Y1011100D02*
X48661D01*
Y1007900D01*
X42461D01*
Y1011100D01*
G01X42883Y1060000D02*
Y1063100D01*
X43803D01*
X44110Y1062945D01*
X44340Y1062583D01*
X44417Y1062170D01*
X44340Y1061757D01*
X44148Y1061447D01*
X43803Y1061292D01*
X42883D01*
G01X47593Y1062842D02*
X47363Y1062997D01*
X47095Y1063100D01*
X46788D01*
X46443Y1062945D01*
X46175Y1062687D01*
X45983Y1062377D01*
X45830Y1061860D01*
X45792Y1061395D01*
X45868Y1060930D01*
X45983Y1060620D01*
X46213Y1060310D01*
X46482Y1060103D01*
X46750Y1060000D01*
X47018D01*
X47287Y1060103D01*
X47517Y1060258D01*
X47708Y1060465D01*
G01X49007D02*
X49237Y1060207D01*
X49505Y1060052D01*
X49850Y1060000D01*
X50195Y1060103D01*
X50463Y1060310D01*
X50655Y1060672D01*
X50693Y1061085D01*
X50617Y1061498D01*
X50425Y1061757D01*
X50157Y1061963D01*
X49888Y1062015D01*
X49620Y1061963D01*
X49275Y1061757D01*
X49390Y1063100D01*
X50425D01*
G01X53410Y1060000D02*
Y1063100D01*
X51992Y1060878D01*
X53908D01*
G01X42874Y1080172D02*
Y1069403D01*
X47874Y1064403D01*
G01D02*
X84212D01*
Y1080172D01*
G01Y1089972D02*
Y1105741D01*
X47874D01*
X42874Y1100741D01*
Y1089972D01*
G01X56913Y1132000D02*
X54487D01*
G01X40307Y1131000D02*
Y1134100D01*
X41073D01*
X41380Y1133945D01*
X41610Y1133738D01*
X41802Y1133428D01*
X41955Y1133067D01*
X41993Y1132550D01*
X41955Y1132033D01*
X41802Y1131672D01*
X41610Y1131362D01*
X41380Y1131155D01*
X41073Y1131000D01*
X40307D01*
G01X44250D02*
Y1134100D01*
X43790Y1133480D01*
G01Y1131000D02*
X44710D01*
G01X47810D02*
Y1134100D01*
X46392Y1131878D01*
X48308D01*
G01X49722Y1133583D02*
X49952Y1133893D01*
X50220Y1134048D01*
X50527Y1134100D01*
X50910Y1133997D01*
X51178Y1133738D01*
X51255Y1133428D01*
X51217Y1133118D01*
X51063Y1132860D01*
X50297Y1132343D01*
X49952Y1131982D01*
X49722Y1131465D01*
X49645Y1131000D01*
X51255D01*
G01X53043Y1133450D02*
Y1138850D01*
G01X53543D02*
Y1133450D01*
G01X54043D02*
Y1138850D01*
G01X67043Y1133350D02*
X52543D01*
Y1138950D01*
X67043D01*
Y1133350D01*
G01X53587Y1140500D02*
X56013D01*
G01X40307Y1141000D02*
Y1144100D01*
X41073D01*
X41380Y1143945D01*
X41610Y1143738D01*
X41802Y1143428D01*
X41955Y1143067D01*
X41993Y1142550D01*
X41955Y1142033D01*
X41802Y1141672D01*
X41610Y1141362D01*
X41380Y1141155D01*
X41073Y1141000D01*
X40307D01*
G01X43522Y1143583D02*
X43752Y1143893D01*
X44020Y1144048D01*
X44327Y1144100D01*
X44710Y1143997D01*
X44978Y1143738D01*
X45055Y1143428D01*
X45017Y1143118D01*
X44863Y1142860D01*
X44097Y1142343D01*
X43752Y1141982D01*
X43522Y1141465D01*
X43445Y1141000D01*
X45055D01*
G01X46622Y1142292D02*
X46890Y1142653D01*
X47120Y1142860D01*
X47427Y1142963D01*
X47695Y1142860D01*
X47887Y1142653D01*
X48040Y1142343D01*
X48078Y1141982D01*
X48040Y1141672D01*
X47887Y1141362D01*
X47657Y1141103D01*
X47388Y1141000D01*
X47082Y1141103D01*
X46813Y1141413D01*
X46660Y1141878D01*
X46622Y1142395D01*
X46698Y1143067D01*
X46813Y1143428D01*
X47005Y1143790D01*
X47273Y1144048D01*
X47542Y1144100D01*
X47810Y1143997D01*
X48002Y1143738D01*
G01X50450Y1144100D02*
X50143Y1143997D01*
X49913Y1143738D01*
X49760Y1143428D01*
X49645Y1143015D01*
X49607Y1142550D01*
X49645Y1142085D01*
X49760Y1141672D01*
X49913Y1141362D01*
X50143Y1141103D01*
X50450Y1141000D01*
X50757Y1141103D01*
X50987Y1141362D01*
X51140Y1141672D01*
X51255Y1142085D01*
X51293Y1142550D01*
X51255Y1143015D01*
X51140Y1143428D01*
X50987Y1143738D01*
X50757Y1143997D01*
X50450Y1144100D01*
G01X53443Y1149250D02*
X59643D01*
Y1146050D01*
X53443D01*
Y1149250D01*
G01X59143Y1127050D02*
X52943D01*
Y1130250D01*
X59143D01*
Y1127050D01*
G01X49587Y1171500D02*
X52013D01*
G01X37807Y1170000D02*
Y1173100D01*
X38573D01*
X38880Y1172945D01*
X39110Y1172738D01*
X39302Y1172428D01*
X39455Y1172067D01*
X39493Y1171550D01*
X39455Y1171033D01*
X39302Y1170672D01*
X39110Y1170362D01*
X38880Y1170155D01*
X38573Y1170000D01*
X37807D01*
G01X41022Y1172583D02*
X41252Y1172893D01*
X41520Y1173048D01*
X41827Y1173100D01*
X42210Y1172997D01*
X42478Y1172738D01*
X42555Y1172428D01*
X42517Y1172118D01*
X42363Y1171860D01*
X41597Y1171343D01*
X41252Y1170982D01*
X41022Y1170465D01*
X40945Y1170000D01*
X42555D01*
G01X44007Y1170465D02*
X44237Y1170207D01*
X44505Y1170052D01*
X44850Y1170000D01*
X45195Y1170103D01*
X45463Y1170310D01*
X45655Y1170672D01*
X45693Y1171085D01*
X45617Y1171498D01*
X45425Y1171757D01*
X45157Y1171963D01*
X44888Y1172015D01*
X44620Y1171963D01*
X44275Y1171757D01*
X44390Y1173100D01*
X45425D01*
G01X47873Y1170000D02*
X47950Y1170672D01*
X48065Y1171240D01*
X48218Y1171757D01*
X48410Y1172325D01*
X48717Y1173100D01*
X47183D01*
G01X53073Y1172400D02*
X53173Y1175100D01*
Y1172000D01*
G01X52780Y1175272D02*
Y1171728D01*
X59866D01*
Y1175272D01*
X52858D01*
G01X53400Y1165600D02*
X59600D01*
Y1162400D01*
X53400D01*
Y1165600D01*
G01X59600Y1150400D02*
X53400D01*
Y1153600D01*
X59600D01*
Y1150400D01*
G01Y1166900D02*
X53400D01*
Y1170100D01*
X59600D01*
Y1166900D01*
G01Y1154400D02*
X53400D01*
Y1157600D01*
X59600D01*
Y1154400D01*
G01Y1158400D02*
X53400D01*
Y1161600D01*
X59600D01*
Y1158400D01*
G01X67043Y1187850D02*
X53043D01*
Y1193450D01*
X67043D01*
Y1187850D01*
G01X51363Y1193030D02*
X48937D01*
G01X37807Y1189000D02*
Y1192100D01*
X38573D01*
X38880Y1191945D01*
X39110Y1191738D01*
X39302Y1191428D01*
X39455Y1191067D01*
X39493Y1190550D01*
X39455Y1190033D01*
X39302Y1189672D01*
X39110Y1189362D01*
X38880Y1189155D01*
X38573Y1189000D01*
X37807D01*
G01X41750D02*
Y1192100D01*
X41290Y1191480D01*
G01Y1189000D02*
X42210D01*
G01X45310D02*
Y1192100D01*
X43892Y1189878D01*
X45808D01*
G01X48410Y1189000D02*
Y1192100D01*
X46992Y1189878D01*
X48908D01*
G01X53543Y1193350D02*
Y1187950D01*
G01X54043D02*
Y1193350D01*
G01X49587Y1184000D02*
X52013D01*
G01X40807Y1178500D02*
Y1181600D01*
X41573D01*
X41880Y1181445D01*
X42110Y1181238D01*
X42302Y1180928D01*
X42455Y1180567D01*
X42493Y1180050D01*
X42455Y1179533D01*
X42302Y1179172D01*
X42110Y1178862D01*
X41880Y1178655D01*
X41573Y1178500D01*
X40807D01*
G01X44022Y1181083D02*
X44252Y1181393D01*
X44520Y1181548D01*
X44827Y1181600D01*
X45210Y1181497D01*
X45478Y1181238D01*
X45555Y1180928D01*
X45517Y1180618D01*
X45363Y1180360D01*
X44597Y1179843D01*
X44252Y1179482D01*
X44022Y1178965D01*
X43945Y1178500D01*
X45555D01*
G01X47007Y1178965D02*
X47237Y1178707D01*
X47505Y1178552D01*
X47850Y1178500D01*
X48195Y1178603D01*
X48463Y1178810D01*
X48655Y1179172D01*
X48693Y1179585D01*
X48617Y1179998D01*
X48425Y1180257D01*
X48157Y1180463D01*
X47888Y1180515D01*
X47620Y1180463D01*
X47275Y1180257D01*
X47390Y1181600D01*
X48425D01*
G01X50950Y1178500D02*
X51218Y1178552D01*
X51525Y1178707D01*
X51717Y1178965D01*
X51793Y1179327D01*
X51717Y1179688D01*
X51487Y1179998D01*
X51142Y1180153D01*
X50758D01*
X50528Y1180257D01*
X50337Y1180515D01*
X50260Y1180877D01*
X50375Y1181238D01*
X50643Y1181497D01*
X50950Y1181600D01*
X51257Y1181497D01*
X51525Y1181238D01*
X51640Y1180877D01*
X51563Y1180515D01*
X51372Y1180257D01*
X51142Y1180153D01*
X50758D01*
X50413Y1179998D01*
X50183Y1179688D01*
X50107Y1179327D01*
X50183Y1178965D01*
X50375Y1178707D01*
X50682Y1178552D01*
X50950Y1178500D01*
G01X53073Y1182900D02*
X53173Y1185600D01*
Y1182500D01*
G01X52780Y1185772D02*
Y1182228D01*
X59866D01*
Y1185772D01*
X52858D01*
G01X59320Y1194637D02*
Y1197063D01*
G01X52570Y1195267D02*
X49470D01*
Y1196033D01*
X49625Y1196340D01*
X49832Y1196570D01*
X50142Y1196762D01*
X50503Y1196915D01*
X51020Y1196953D01*
X51537Y1196915D01*
X51898Y1196762D01*
X52208Y1196570D01*
X52415Y1196340D01*
X52570Y1196033D01*
Y1195267D01*
G01X49987Y1198482D02*
X49677Y1198712D01*
X49522Y1198980D01*
X49470Y1199287D01*
X49573Y1199670D01*
X49832Y1199938D01*
X50142Y1200015D01*
X50452Y1199977D01*
X50710Y1199823D01*
X51227Y1199057D01*
X51588Y1198712D01*
X52105Y1198482D01*
X52570Y1198405D01*
Y1200015D01*
G01X52105Y1201467D02*
X52363Y1201697D01*
X52518Y1201965D01*
X52570Y1202310D01*
X52467Y1202655D01*
X52260Y1202923D01*
X51898Y1203115D01*
X51485Y1203153D01*
X51072Y1203077D01*
X50813Y1202885D01*
X50607Y1202617D01*
X50555Y1202348D01*
X50607Y1202080D01*
X50813Y1201735D01*
X49470Y1201850D01*
Y1202885D01*
G01X52208Y1204758D02*
X52467Y1205027D01*
X52570Y1205333D01*
X52467Y1205640D01*
X52157Y1205908D01*
X51692Y1206100D01*
X51227Y1206177D01*
X50658D01*
X50193Y1206100D01*
X49780Y1205908D01*
X49573Y1205678D01*
X49470Y1205410D01*
X49573Y1205103D01*
X49780Y1204873D01*
X50090Y1204720D01*
X50503Y1204643D01*
X50865Y1204720D01*
X51227Y1204912D01*
X51433Y1205142D01*
X51485Y1205410D01*
X51382Y1205717D01*
X51123Y1205947D01*
X50658Y1206177D01*
G01X54228Y1195280D02*
X57772D01*
Y1202366D01*
X54228D01*
Y1195358D01*
G01X59600Y1176900D02*
X53400D01*
Y1180100D01*
X59600D01*
Y1176900D01*
G01X56000Y1205273D02*
Y1207513D01*
G01X54375Y1206300D02*
X57625D01*
G01X57100Y1195573D02*
X54400Y1195673D01*
X57500D01*
G01X48400Y1213500D02*
Y1207500D01*
X54400D01*
G01X42920Y1223360D02*
X42868Y1223053D01*
X42662Y1222785D01*
X42352Y1222555D01*
X41990Y1222402D01*
X41577Y1222325D01*
X41163D01*
X40750Y1222402D01*
X40388Y1222555D01*
X40078Y1222785D01*
X39872Y1223053D01*
X39820Y1223360D01*
X39872Y1223667D01*
X40078Y1223935D01*
X40388Y1224165D01*
X40750Y1224318D01*
X41163Y1224395D01*
X41577D01*
X41990Y1224318D01*
X42352Y1224165D01*
X42662Y1223935D01*
X42868Y1223667D01*
X42920Y1223360D01*
G01X42093Y1223667D02*
X42920Y1224127D01*
G01Y1226460D02*
X39820D01*
X40440Y1226000D01*
G01X42920D02*
Y1226920D01*
G01X41628Y1228832D02*
X41267Y1229100D01*
X41060Y1229330D01*
X40957Y1229637D01*
X41060Y1229905D01*
X41267Y1230097D01*
X41577Y1230250D01*
X41938Y1230288D01*
X42248Y1230250D01*
X42558Y1230097D01*
X42817Y1229867D01*
X42920Y1229598D01*
X42817Y1229292D01*
X42507Y1229023D01*
X42042Y1228870D01*
X41525Y1228832D01*
X40853Y1228908D01*
X40492Y1229023D01*
X40130Y1229215D01*
X39872Y1229483D01*
X39820Y1229752D01*
X39923Y1230020D01*
X40182Y1230212D01*
G01X50040Y1223200D02*
X50787Y1222575D01*
X51627Y1222200D01*
X52373D01*
X53120Y1222575D01*
X53680Y1223200D01*
X53960Y1224075D01*
X53773Y1224950D01*
X53307Y1225700D01*
X52467Y1226200D01*
X51347Y1226450D01*
X50693Y1226950D01*
X50413Y1227825D01*
X50600Y1228700D01*
X51067Y1229325D01*
X51720Y1229700D01*
X52373D01*
X53027Y1229450D01*
X53587Y1228825D01*
G01X57820Y1221950D02*
X61180Y1229700D01*
G01X64853Y1222200D02*
Y1229700D01*
X69147Y1222200D01*
Y1229700D01*
G01X54400Y1231122D02*
X48400D01*
Y1225122D01*
G01X74252Y44685D02*
Y7283D01*
X80158Y1378D01*
X99489D01*
X105394Y7283D01*
Y43307D01*
G02X106772Y44685I1378J0D01*
G02X108150Y43307I0J-1378D01*
G01Y32635D01*
G01X69727Y68000D02*
X67487D01*
G01X68700Y66375D02*
Y69625D01*
G01X59362Y61873D02*
Y65811D01*
G01X61724Y61873D02*
Y65811D01*
X59756Y63842D01*
X61724Y61873D01*
G01X77773Y56500D02*
X80013D01*
G01X78800Y58125D02*
Y54875D01*
G01X67587Y53500D02*
X70013D01*
G01X70807Y49500D02*
Y52600D01*
X71573D01*
X71880Y52445D01*
X72110Y52238D01*
X72302Y51928D01*
X72455Y51567D01*
X72493Y51050D01*
X72455Y50533D01*
X72302Y50172D01*
X72110Y49862D01*
X71880Y49655D01*
X71573Y49500D01*
X70807D01*
G01X74022Y52083D02*
X74252Y52393D01*
X74520Y52548D01*
X74827Y52600D01*
X75210Y52497D01*
X75478Y52238D01*
X75555Y51928D01*
X75517Y51618D01*
X75363Y51360D01*
X74597Y50843D01*
X74252Y50482D01*
X74022Y49965D01*
X73945Y49500D01*
X75555D01*
G01X78310D02*
Y52600D01*
X76892Y50378D01*
X78808D01*
G01X80107Y50120D02*
X80337Y49758D01*
X80643Y49552D01*
X80988Y49500D01*
X81295Y49552D01*
X81602Y49810D01*
X81793Y50120D01*
X81832Y50430D01*
X81755Y50792D01*
X81487Y51050D01*
X81218Y51153D01*
X80873D01*
G01X81218D02*
X81448Y51308D01*
X81640Y51567D01*
X81717Y51877D01*
X81640Y52187D01*
X81448Y52445D01*
X81103Y52600D01*
X80758Y52548D01*
X80413Y52342D01*
G01X69823Y58114D02*
Y54570D01*
X76909D01*
Y58114D01*
X69901D01*
G01X70116Y55242D02*
X70216Y57942D01*
Y54842D01*
G01X66143Y59442D02*
Y53242D01*
X62943D01*
Y59442D01*
X66143D01*
G01X129292Y47833D02*
X74252D01*
G01X80100Y60700D02*
X69900D01*
Y65300D01*
X80100D01*
Y60700D01*
G01X73757Y84669D02*
Y93331D01*
X63243D01*
Y84669D01*
X73757D01*
G01X77273Y78000D02*
X79513D01*
G01X78300Y79625D02*
Y76375D01*
G01X68087Y78000D02*
X70513D01*
G01X69780Y76964D02*
Y73420D01*
X76866D01*
Y76964D01*
X69858D01*
G01X70073Y74092D02*
X70173Y76792D01*
Y73692D01*
G01X64773Y70500D02*
X67013D01*
G01X65800Y72125D02*
Y68875D01*
G01X56823Y72114D02*
Y68570D01*
X63909D01*
Y72114D01*
X56901D01*
G01X57116Y69242D02*
X57216Y71942D01*
Y68842D01*
G01X78600Y91600D02*
Y85400D01*
X75400D01*
Y91600D01*
X78600D01*
G01X74900Y65900D02*
Y72100D01*
X78100D01*
Y65900D01*
X74900D01*
G01X61943Y76942D02*
X68143D01*
Y73742D01*
X61943D01*
Y76942D01*
G01X70900Y65900D02*
Y72100D01*
X74100D01*
Y65900D01*
X70900D01*
G01X70100Y79400D02*
X63900D01*
Y82600D01*
X70100D01*
Y79400D01*
G01X73757Y101669D02*
Y110331D01*
X63243D01*
Y101669D01*
X73757D01*
G01X62773Y114000D02*
X65013D01*
G01X63800Y115625D02*
Y112375D01*
G01X60273Y100500D02*
X62513D01*
G01X61300Y102125D02*
Y98875D01*
G01X78600Y109100D02*
Y102900D01*
X75400D01*
Y109100D01*
X78600D01*
G01X61100D02*
Y102900D01*
X57900D01*
Y109100D01*
X61100D01*
G01Y94100D02*
Y87900D01*
X57900D01*
Y94100D01*
X61100D01*
G01X70100Y96400D02*
X63900D01*
Y99600D01*
X70100D01*
Y96400D01*
G01X69227Y125500D02*
X66987D01*
G01X68200Y123875D02*
Y127125D01*
G01X59862Y118373D02*
Y122311D01*
G01X62224Y118373D02*
Y122311D01*
X60256Y120342D01*
X62224Y118373D01*
G01X69807Y114600D02*
Y112378D01*
X69960Y111913D01*
X70267Y111603D01*
X70650Y111500D01*
X71033Y111603D01*
X71340Y111913D01*
X71493Y112378D01*
Y114600D01*
G01X72907Y112120D02*
X73137Y111758D01*
X73443Y111552D01*
X73788Y111500D01*
X74095Y111552D01*
X74402Y111810D01*
X74593Y112120D01*
X74632Y112430D01*
X74555Y112792D01*
X74287Y113050D01*
X74018Y113153D01*
X73673D01*
G01X74018D02*
X74248Y113308D01*
X74440Y113567D01*
X74517Y113877D01*
X74440Y114187D01*
X74248Y114445D01*
X73903Y114600D01*
X73558Y114548D01*
X73213Y114342D01*
G01X77310Y111500D02*
Y114600D01*
X75892Y112378D01*
X77808D01*
G01X79950Y114600D02*
X79643Y114497D01*
X79413Y114238D01*
X79260Y113928D01*
X79145Y113515D01*
X79107Y113050D01*
X79145Y112585D01*
X79260Y112172D01*
X79413Y111862D01*
X79643Y111603D01*
X79950Y111500D01*
X80257Y111603D01*
X80487Y111862D01*
X80640Y112172D01*
X80755Y112585D01*
X80793Y113050D01*
X80755Y113515D01*
X80640Y113928D01*
X80487Y114238D01*
X80257Y114497D01*
X79950Y114600D01*
G01X61773Y131000D02*
X64013D01*
G01X62800Y132625D02*
Y129375D01*
G01X57323Y128614D02*
Y125070D01*
X64409D01*
Y128614D01*
X57401D01*
G01X57616Y125742D02*
X57716Y128442D01*
Y125342D01*
G01X73900Y122900D02*
Y129100D01*
X77100D01*
Y122900D01*
X73900D01*
G01X69900D02*
Y129100D01*
X73100D01*
Y122900D01*
X69900D01*
G01X68500Y131000D02*
Y144000D01*
X83500D01*
Y131000D01*
X68500D01*
G01X78943Y117200D02*
X68743D01*
Y121800D01*
X78943D01*
Y117200D01*
G01X71660Y145720D02*
X71353Y145772D01*
X71085Y145978D01*
X70855Y146288D01*
X70702Y146650D01*
X70625Y147063D01*
Y147477D01*
X70702Y147890D01*
X70855Y148252D01*
X71085Y148562D01*
X71353Y148768D01*
X71660Y148820D01*
X71967Y148768D01*
X72235Y148562D01*
X72465Y148252D01*
X72618Y147890D01*
X72695Y147477D01*
Y147063D01*
X72618Y146650D01*
X72465Y146288D01*
X72235Y145978D01*
X71967Y145772D01*
X71660Y145720D01*
G01X71967Y146547D02*
X72427Y145720D01*
G01X74760D02*
Y148820D01*
X74300Y148200D01*
G01Y145720D02*
X75220D01*
G01X77017Y146340D02*
X77247Y145978D01*
X77553Y145772D01*
X77898Y145720D01*
X78205Y145772D01*
X78512Y146030D01*
X78703Y146340D01*
X78742Y146650D01*
X78665Y147012D01*
X78397Y147270D01*
X78128Y147373D01*
X77783D01*
G01X78128D02*
X78358Y147528D01*
X78550Y147787D01*
X78627Y148097D01*
X78550Y148407D01*
X78358Y148665D01*
X78013Y148820D01*
X77668Y148768D01*
X77323Y148562D01*
G01X60969Y160031D02*
Y170800D01*
X55969Y175800D01*
G01X55461Y285328D02*
X61661D01*
Y282128D01*
X55461D01*
Y285328D01*
G01X68161Y283828D02*
Y277628D01*
X64961D01*
Y283828D01*
X68161D01*
G01X54900Y287900D02*
Y294100D01*
X58100D01*
Y287900D01*
X54900D01*
G01X73400Y308200D02*
Y316200D01*
X75900D01*
X76700Y315800D01*
X77200Y315267D01*
X77400Y314200D01*
X77200Y313133D01*
X76600Y312467D01*
X75900Y312067D01*
X73400D01*
G01X75900D02*
X77400Y308200D01*
G01X81900Y311800D02*
X85100D01*
X84800Y312733D01*
X84300Y313267D01*
X83600Y313533D01*
X82900Y313400D01*
X82300Y313000D01*
X81900Y312067D01*
X81700Y311266D01*
Y310467D01*
X81900Y309667D01*
X82400Y308867D01*
X83000Y308333D01*
X83700Y308200D01*
X84400Y308467D01*
X85100Y309266D01*
G01X89600Y313533D02*
X91400Y308200D01*
X93200Y313533D01*
G01X99400Y307933D02*
X99200Y308067D01*
Y308333D01*
X99400Y308467D01*
X99600Y308333D01*
Y308067D01*
X99400Y307933D01*
G01Y311533D02*
X99200Y311667D01*
Y311933D01*
X99400Y312067D01*
X99600Y311933D01*
Y311667D01*
X99400Y311533D01*
G01X105200Y308200D02*
Y316200D01*
X107200D01*
X108000Y315800D01*
X108600Y315267D01*
X109100Y314467D01*
X109500Y313533D01*
X109600Y312200D01*
X109500Y310867D01*
X109100Y309933D01*
X108600Y309133D01*
X108000Y308600D01*
X107200Y308200D01*
X105200D01*
G01X69227Y405000D02*
X66987D01*
G01X68200Y403375D02*
Y406625D01*
G01X61724Y406909D02*
Y410847D01*
X59756Y408878D01*
X61724Y406909D01*
G01X59362D02*
Y410847D01*
G01X78273Y403500D02*
X80513D01*
G01X79300Y405125D02*
Y401875D01*
G01X67587Y398000D02*
X70013D01*
G01X68307Y393500D02*
Y396600D01*
X69073D01*
X69380Y396445D01*
X69610Y396238D01*
X69802Y395928D01*
X69955Y395567D01*
X69993Y395050D01*
X69955Y394533D01*
X69802Y394172D01*
X69610Y393862D01*
X69380Y393655D01*
X69073Y393500D01*
X68307D01*
G01X71522Y396083D02*
X71752Y396393D01*
X72020Y396548D01*
X72327Y396600D01*
X72710Y396497D01*
X72978Y396238D01*
X73055Y395928D01*
X73017Y395618D01*
X72863Y395360D01*
X72097Y394843D01*
X71752Y394482D01*
X71522Y393965D01*
X71445Y393500D01*
X73055D01*
G01X75810D02*
Y396600D01*
X74392Y394378D01*
X76308D01*
G01X77798Y393862D02*
X78067Y393603D01*
X78373Y393500D01*
X78680Y393603D01*
X78948Y393913D01*
X79140Y394378D01*
X79217Y394843D01*
Y395412D01*
X79140Y395877D01*
X78948Y396290D01*
X78718Y396497D01*
X78450Y396600D01*
X78143Y396497D01*
X77913Y396290D01*
X77760Y395980D01*
X77683Y395567D01*
X77760Y395205D01*
X77952Y394843D01*
X78182Y394637D01*
X78450Y394585D01*
X78757Y394688D01*
X78987Y394947D01*
X79217Y395412D01*
G01X70116Y400278D02*
X70216Y402978D01*
Y399878D01*
G01X69823Y403150D02*
Y399606D01*
X76909D01*
Y403150D01*
X69901D01*
G01X70400Y411600D02*
X76600D01*
Y408400D01*
X70400D01*
Y411600D01*
G01X61443Y402978D02*
X67643D01*
Y399778D01*
X61443D01*
Y402978D01*
G01X70400Y407600D02*
X76600D01*
Y404400D01*
X70400D01*
Y407600D01*
G01X73757Y430669D02*
Y439331D01*
X63243D01*
Y430669D01*
X73757D01*
G01X64773Y415500D02*
X67013D01*
G01X65800Y417125D02*
Y413875D01*
G01X57116Y414278D02*
X57216Y416978D01*
Y413878D01*
G01X56823Y417150D02*
Y413606D01*
X63909D01*
Y417150D01*
X56901D01*
G01X78273Y421500D02*
X80513D01*
G01X79300Y423125D02*
Y419875D01*
G01X69587Y423500D02*
X72013D01*
G01X70073Y419128D02*
X70173Y421828D01*
Y418728D01*
G01X69780Y422000D02*
Y418456D01*
X76866D01*
Y422000D01*
X69858D01*
G01X78600Y437100D02*
Y430900D01*
X75400D01*
Y437100D01*
X78600D01*
G01X61943Y421978D02*
X68143D01*
Y418778D01*
X61943D01*
Y421978D01*
G01X69600Y425400D02*
X63400D01*
Y428600D01*
X69600D01*
Y425400D01*
G01X80600Y412700D02*
X70400D01*
Y417300D01*
X80600D01*
Y412700D01*
G01X75307Y447100D02*
Y444878D01*
X75460Y444413D01*
X75767Y444103D01*
X76150Y444000D01*
X76533Y444103D01*
X76840Y444413D01*
X76993Y444878D01*
Y447100D01*
G01X78407Y444620D02*
X78637Y444258D01*
X78943Y444052D01*
X79288Y444000D01*
X79595Y444052D01*
X79902Y444310D01*
X80093Y444620D01*
X80132Y444930D01*
X80055Y445292D01*
X79787Y445550D01*
X79518Y445653D01*
X79173D01*
G01X79518D02*
X79748Y445808D01*
X79940Y446067D01*
X80017Y446377D01*
X79940Y446687D01*
X79748Y446945D01*
X79403Y447100D01*
X79058Y447048D01*
X78713Y446842D01*
G01X81622Y445292D02*
X81890Y445653D01*
X82120Y445860D01*
X82427Y445963D01*
X82695Y445860D01*
X82887Y445653D01*
X83040Y445343D01*
X83078Y444982D01*
X83040Y444672D01*
X82887Y444362D01*
X82657Y444103D01*
X82388Y444000D01*
X82082Y444103D01*
X81813Y444413D01*
X81660Y444878D01*
X81622Y445395D01*
X81698Y446067D01*
X81813Y446428D01*
X82005Y446790D01*
X82273Y447048D01*
X82542Y447100D01*
X82810Y446997D01*
X83002Y446738D01*
G01X84722Y446583D02*
X84952Y446893D01*
X85220Y447048D01*
X85527Y447100D01*
X85910Y446997D01*
X86178Y446738D01*
X86255Y446428D01*
X86217Y446118D01*
X86063Y445860D01*
X85297Y445343D01*
X84952Y444982D01*
X84722Y444465D01*
X84645Y444000D01*
X86255D01*
G01X73757Y447169D02*
Y455831D01*
X63243D01*
Y447169D01*
X73757D01*
G01X75307Y442100D02*
Y439878D01*
X75460Y439413D01*
X75767Y439103D01*
X76150Y439000D01*
X76533Y439103D01*
X76840Y439413D01*
X76993Y439878D01*
Y442100D01*
G01X78407Y439620D02*
X78637Y439258D01*
X78943Y439052D01*
X79288Y439000D01*
X79595Y439052D01*
X79902Y439310D01*
X80093Y439620D01*
X80132Y439930D01*
X80055Y440292D01*
X79787Y440550D01*
X79518Y440653D01*
X79173D01*
G01X79518D02*
X79748Y440808D01*
X79940Y441067D01*
X80017Y441377D01*
X79940Y441687D01*
X79748Y441945D01*
X79403Y442100D01*
X79058Y442048D01*
X78713Y441842D01*
G01X81622Y440292D02*
X81890Y440653D01*
X82120Y440860D01*
X82427Y440963D01*
X82695Y440860D01*
X82887Y440653D01*
X83040Y440343D01*
X83078Y439982D01*
X83040Y439672D01*
X82887Y439362D01*
X82657Y439103D01*
X82388Y439000D01*
X82082Y439103D01*
X81813Y439413D01*
X81660Y439878D01*
X81622Y440395D01*
X81698Y441067D01*
X81813Y441428D01*
X82005Y441790D01*
X82273Y442048D01*
X82542Y442100D01*
X82810Y441997D01*
X83002Y441738D01*
G01X84607Y439620D02*
X84837Y439258D01*
X85143Y439052D01*
X85488Y439000D01*
X85795Y439052D01*
X86102Y439310D01*
X86293Y439620D01*
X86332Y439930D01*
X86255Y440292D01*
X85987Y440550D01*
X85718Y440653D01*
X85373D01*
G01X85718D02*
X85948Y440808D01*
X86140Y441067D01*
X86217Y441377D01*
X86140Y441687D01*
X85948Y441945D01*
X85603Y442100D01*
X85258Y442048D01*
X84913Y441842D01*
G01X60773Y441000D02*
X63013D01*
G01X61800Y442625D02*
Y439375D01*
G01X60773Y457500D02*
X63013D01*
G01X61800Y459125D02*
Y455875D01*
G01X78600Y454600D02*
Y448400D01*
X75400D01*
Y454600D01*
X78600D01*
G01X61100Y439600D02*
Y433400D01*
X57900D01*
Y439600D01*
X61100D01*
G01Y453600D02*
Y447400D01*
X57900D01*
Y453600D01*
X61100D01*
G01X69600Y441900D02*
X63400D01*
Y445100D01*
X69600D01*
Y441900D01*
G01X67227Y469500D02*
X64987D01*
G01X66200Y467875D02*
Y471125D01*
G01X61724Y461909D02*
Y465847D01*
X59756Y463878D01*
X61724Y461909D01*
G01X59362D02*
Y465847D01*
G01X64273Y473500D02*
X66513D01*
G01X65300Y475125D02*
Y471875D01*
G01X57116Y469278D02*
X57216Y471978D01*
Y468878D01*
G01X56823Y472150D02*
Y468606D01*
X63909D01*
Y472150D01*
X56901D01*
G01X67400Y476600D02*
X73600D01*
Y473400D01*
X67400D01*
Y476600D01*
G01X55475Y482100D02*
X61675D01*
Y478900D01*
X55475D01*
Y482100D01*
G01X63100Y473400D02*
X56900D01*
Y476600D01*
X63100D01*
Y473400D01*
G01X69700Y460900D02*
Y471100D01*
X74300D01*
Y460900D01*
X69700D01*
G01X75897Y494710D02*
Y492488D01*
X76050Y492023D01*
X76357Y491713D01*
X76740Y491610D01*
X77123Y491713D01*
X77430Y492023D01*
X77583Y492488D01*
Y494710D01*
G01X78997Y492230D02*
X79227Y491868D01*
X79533Y491662D01*
X79878Y491610D01*
X80185Y491662D01*
X80492Y491920D01*
X80683Y492230D01*
X80722Y492540D01*
X80645Y492902D01*
X80377Y493160D01*
X80108Y493263D01*
X79763D01*
G01X80108D02*
X80338Y493418D01*
X80530Y493677D01*
X80607Y493987D01*
X80530Y494297D01*
X80338Y494555D01*
X79993Y494710D01*
X79648Y494658D01*
X79303Y494452D01*
G01X82097Y492230D02*
X82327Y491868D01*
X82633Y491662D01*
X82978Y491610D01*
X83285Y491662D01*
X83592Y491920D01*
X83783Y492230D01*
X83822Y492540D01*
X83745Y492902D01*
X83477Y493160D01*
X83208Y493263D01*
X82863D01*
G01X83208D02*
X83438Y493418D01*
X83630Y493677D01*
X83707Y493987D01*
X83630Y494297D01*
X83438Y494555D01*
X83093Y494710D01*
X82748Y494658D01*
X82403Y494452D01*
G01X86040Y494710D02*
X85733Y494607D01*
X85503Y494348D01*
X85350Y494038D01*
X85235Y493625D01*
X85197Y493160D01*
X85235Y492695D01*
X85350Y492282D01*
X85503Y491972D01*
X85733Y491713D01*
X86040Y491610D01*
X86347Y491713D01*
X86577Y491972D01*
X86730Y492282D01*
X86845Y492695D01*
X86883Y493160D01*
X86845Y493625D01*
X86730Y494038D01*
X86577Y494348D01*
X86347Y494607D01*
X86040Y494710D01*
G01X74125Y497017D02*
Y499517D01*
X73805Y499017D01*
G01Y497017D02*
X74445D01*
G01X75738Y497392D02*
X75898Y497184D01*
X76085Y497059D01*
X76325Y497017D01*
X76565Y497100D01*
X76752Y497267D01*
X76885Y497559D01*
X76912Y497892D01*
X76858Y498225D01*
X76725Y498434D01*
X76538Y498600D01*
X76352Y498642D01*
X76165Y498600D01*
X75925Y498434D01*
X76005Y499517D01*
X76725D01*
G01X77700Y496500D02*
Y498500D01*
G01X74429Y502895D02*
Y500429D01*
G01D02*
X76920D01*
G01X55400Y502100D02*
X61600D01*
Y498900D01*
X55400D01*
Y502100D01*
G01Y497100D02*
X61600D01*
Y493900D01*
X55400D01*
Y497100D01*
G01Y492100D02*
X61600D01*
Y488900D01*
X55400D01*
Y492100D01*
G01Y487100D02*
X61600D01*
Y483900D01*
X55400D01*
Y487100D01*
G01X68820Y506490D02*
X71320D01*
X70820Y506810D01*
G01X68820D02*
Y506170D01*
G01Y503970D02*
X71320D01*
X69528Y504957D01*
Y503623D01*
G01X71192Y515275D02*
X71234Y515088D01*
X71359Y514875D01*
X71567Y514742D01*
X71859Y514688D01*
X72150Y514742D01*
X72400Y514902D01*
X72525Y515142D01*
Y515408D01*
X72609Y515568D01*
X72817Y515702D01*
X73109Y515755D01*
X73400Y515675D01*
X73609Y515488D01*
X73692Y515275D01*
X73609Y515062D01*
X73400Y514875D01*
X73109Y514795D01*
X72817Y514848D01*
X72609Y514982D01*
X72525Y515142D01*
Y515408D01*
X72400Y515648D01*
X72150Y515808D01*
X71859Y515862D01*
X71567Y515808D01*
X71359Y515675D01*
X71234Y515462D01*
X71192Y515275D01*
G01X75797Y517467D02*
X75850Y518009D01*
X75930Y518467D01*
X76037Y518884D01*
X76170Y519342D01*
X76383Y519967D01*
X75317D01*
G01X72500Y510100D02*
X69500D01*
G01X76910Y516571D02*
X74429D01*
Y514082D01*
G01X69400Y524400D02*
Y530600D01*
X72600D01*
Y524400D01*
X69400D01*
G01X78100Y530600D02*
Y524400D01*
X74900D01*
Y530600D01*
X78100D01*
G01X55400Y527600D02*
X61600D01*
Y524400D01*
X55400D01*
Y527600D01*
G01Y522600D02*
X61600D01*
Y519400D01*
X55400D01*
Y522600D01*
G01Y517600D02*
X61600D01*
Y514400D01*
X55400D01*
Y517600D01*
G01Y512600D02*
X61600D01*
Y509400D01*
X55400D01*
Y512600D01*
G01Y507600D02*
X61600D01*
Y504400D01*
X55400D01*
Y507600D01*
G01X72600Y538600D02*
Y532400D01*
X69400D01*
Y538600D01*
X72600D01*
G01X78100D02*
Y532400D01*
X74900D01*
Y538600D01*
X78100D01*
G01X55475Y537600D02*
X61675D01*
Y534400D01*
X55475D01*
Y537600D01*
G01X55400Y532600D02*
X61600D01*
Y529400D01*
X55400D01*
Y532600D01*
G01X69600Y569600D02*
Y563400D01*
X66400D01*
Y569600D01*
X69600D01*
G01X76600D02*
Y563400D01*
X73400D01*
Y569600D01*
X76600D01*
G01X77400Y590807D02*
X79622D01*
X80087Y590960D01*
X80397Y591267D01*
X80500Y591650D01*
X80397Y592033D01*
X80087Y592340D01*
X79622Y592493D01*
X77400D01*
G01X79880Y593907D02*
X80242Y594137D01*
X80448Y594443D01*
X80500Y594788D01*
X80448Y595095D01*
X80190Y595402D01*
X79880Y595593D01*
X79570Y595632D01*
X79208Y595555D01*
X78950Y595287D01*
X78847Y595018D01*
Y594673D01*
G01Y595018D02*
X78692Y595248D01*
X78433Y595440D01*
X78123Y595517D01*
X77813Y595440D01*
X77555Y595248D01*
X77400Y594903D01*
X77452Y594558D01*
X77658Y594213D01*
G01X77917Y597122D02*
X77607Y597352D01*
X77452Y597620D01*
X77400Y597927D01*
X77503Y598310D01*
X77762Y598578D01*
X78072Y598655D01*
X78382Y598617D01*
X78640Y598463D01*
X79157Y597697D01*
X79518Y597352D01*
X80035Y597122D01*
X80500Y597045D01*
Y598655D01*
G01Y600950D02*
X77400D01*
X78020Y600490D01*
G01X80500D02*
Y601410D01*
G01X66400Y571900D02*
Y578100D01*
X69600D01*
Y571900D01*
X66400D01*
G01X73400D02*
Y578100D01*
X76600D01*
Y571900D01*
X73400D01*
G01X80100Y613100D02*
Y606900D01*
X76900D01*
Y613100D01*
X80100D01*
G01X73600Y639400D02*
X67400D01*
Y642600D01*
X73600D01*
Y639400D01*
G01Y633100D02*
Y626900D01*
X70400D01*
Y633100D01*
X73600D01*
G01X69600D02*
Y626900D01*
X66400D01*
Y633100D01*
X69600D01*
G01X58400Y642600D02*
X64600D01*
Y639400D01*
X58400D01*
Y642600D01*
G01X73600Y655900D02*
X67400D01*
Y659100D01*
X73600D01*
Y655900D01*
G01Y649900D02*
X67400D01*
Y653100D01*
X73600D01*
Y649900D01*
G01Y645400D02*
X67400D01*
Y648600D01*
X73600D01*
Y645400D01*
G01X58400Y661600D02*
X64600D01*
Y658400D01*
X58400D01*
Y661600D01*
G01Y657000D02*
X64600D01*
Y653800D01*
X58400D01*
Y657000D01*
G01Y648600D02*
X64600D01*
Y645400D01*
X58400D01*
Y648600D01*
G01X73600Y683400D02*
X67400D01*
Y686600D01*
X73600D01*
Y683400D01*
G01Y677400D02*
X67400D01*
Y680600D01*
X73600D01*
Y677400D01*
G01Y670900D02*
X67400D01*
Y674100D01*
X73600D01*
Y670900D01*
G01Y664900D02*
X67400D01*
Y668100D01*
X73600D01*
Y664900D01*
G01X58400Y686600D02*
X64600D01*
Y683400D01*
X58400D01*
Y686600D01*
G01Y680600D02*
X64600D01*
Y677400D01*
X58400D01*
Y680600D01*
G01Y674100D02*
X64600D01*
Y670900D01*
X58400D01*
Y674100D01*
G01Y668100D02*
X64600D01*
Y664900D01*
X58400D01*
Y668100D01*
G01X75600Y702400D02*
X69400D01*
Y705600D01*
X75600D01*
Y702400D01*
G01Y707900D02*
X69400D01*
Y711100D01*
X75600D01*
Y707900D01*
G01Y717400D02*
X69400D01*
Y720600D01*
X75600D01*
Y717400D01*
G01Y722400D02*
X69400D01*
Y725600D01*
X75600D01*
Y722400D01*
G01Y713400D02*
X69400D01*
Y716600D01*
X75600D01*
Y713400D01*
G01X69400Y736100D02*
X75600D01*
Y732900D01*
X69400D01*
Y736100D01*
G01Y730600D02*
X75600D01*
Y727400D01*
X69400D01*
Y730600D01*
G01X66587Y761000D02*
X69013D01*
G01X75600Y740900D02*
X69400D01*
Y744100D01*
X75600D01*
Y740900D01*
G01X69400Y740100D02*
X75600D01*
Y736900D01*
X69400D01*
Y740100D01*
G01X75600Y749900D02*
X69400D01*
Y753100D01*
X75600D01*
Y749900D01*
G01X69400Y748100D02*
X75600D01*
Y744900D01*
X69400D01*
Y748100D01*
G01X69227Y768500D02*
X66987D01*
G01X68200Y766875D02*
Y770125D01*
G01X61724Y770295D02*
Y774233D01*
X59756Y772264D01*
X61724Y770295D01*
G01X59362D02*
Y774233D01*
G01X59973Y781300D02*
X62213D01*
G01X61000Y782925D02*
Y779675D01*
G01X79273Y764000D02*
X81513D01*
G01X80300Y765625D02*
Y762375D01*
G01X70807Y758500D02*
Y761600D01*
X71573D01*
X71880Y761445D01*
X72110Y761238D01*
X72302Y760928D01*
X72455Y760567D01*
X72493Y760050D01*
X72455Y759533D01*
X72302Y759172D01*
X72110Y758862D01*
X71880Y758655D01*
X71573Y758500D01*
X70807D01*
G01X74022Y761083D02*
X74252Y761393D01*
X74520Y761548D01*
X74827Y761600D01*
X75210Y761497D01*
X75478Y761238D01*
X75555Y760928D01*
X75517Y760618D01*
X75363Y760360D01*
X74597Y759843D01*
X74252Y759482D01*
X74022Y758965D01*
X73945Y758500D01*
X75555D01*
G01X77007Y758965D02*
X77237Y758707D01*
X77505Y758552D01*
X77850Y758500D01*
X78195Y758603D01*
X78463Y758810D01*
X78655Y759172D01*
X78693Y759585D01*
X78617Y759998D01*
X78425Y760257D01*
X78157Y760463D01*
X77888Y760515D01*
X77620Y760463D01*
X77275Y760257D01*
X77390Y761600D01*
X78425D01*
G01X80107Y758965D02*
X80337Y758707D01*
X80605Y758552D01*
X80950Y758500D01*
X81295Y758603D01*
X81563Y758810D01*
X81755Y759172D01*
X81793Y759585D01*
X81717Y759998D01*
X81525Y760257D01*
X81257Y760463D01*
X80988Y760515D01*
X80720Y760463D01*
X80375Y760257D01*
X80490Y761600D01*
X81525D01*
G01X70116Y763664D02*
X70216Y766364D01*
Y763264D01*
G01X69823Y766536D02*
Y762992D01*
X76909D01*
Y766536D01*
X69901D01*
G01X78673Y784300D02*
X80913D01*
G01X79700Y785925D02*
Y782675D01*
G01X67087Y781000D02*
X69513D01*
G01X68100Y776900D02*
X61900D01*
Y780100D01*
X68100D01*
Y776900D01*
G01X61443Y766364D02*
X67643D01*
Y763164D01*
X61443D01*
Y766364D01*
G01X73600Y774600D02*
Y768400D01*
X70400D01*
Y774600D01*
X73600D01*
G01X79600Y775700D02*
X69400D01*
Y780300D01*
X79600D01*
Y775700D01*
G01X63307Y794100D02*
Y791878D01*
X63460Y791413D01*
X63767Y791103D01*
X64150Y791000D01*
X64533Y791103D01*
X64840Y791413D01*
X64993Y791878D01*
Y794100D01*
G01X66407Y791620D02*
X66637Y791258D01*
X66943Y791052D01*
X67288Y791000D01*
X67595Y791052D01*
X67902Y791310D01*
X68093Y791620D01*
X68132Y791930D01*
X68055Y792292D01*
X67787Y792550D01*
X67518Y792653D01*
X67173D01*
G01X67518D02*
X67748Y792808D01*
X67940Y793067D01*
X68017Y793377D01*
X67940Y793687D01*
X67748Y793945D01*
X67403Y794100D01*
X67058Y794048D01*
X66713Y793842D01*
G01X69622Y792292D02*
X69890Y792653D01*
X70120Y792860D01*
X70427Y792963D01*
X70695Y792860D01*
X70887Y792653D01*
X71040Y792343D01*
X71078Y791982D01*
X71040Y791672D01*
X70887Y791362D01*
X70657Y791103D01*
X70388Y791000D01*
X70082Y791103D01*
X69813Y791413D01*
X69660Y791878D01*
X69622Y792395D01*
X69698Y793067D01*
X69813Y793428D01*
X70005Y793790D01*
X70273Y794048D01*
X70542Y794100D01*
X70810Y793997D01*
X71002Y793738D01*
G01X72607Y791465D02*
X72837Y791207D01*
X73105Y791052D01*
X73450Y791000D01*
X73795Y791103D01*
X74063Y791310D01*
X74255Y791672D01*
X74293Y792085D01*
X74217Y792498D01*
X74025Y792757D01*
X73757Y792963D01*
X73488Y793015D01*
X73220Y792963D01*
X72875Y792757D01*
X72990Y794100D01*
X74025D01*
G01X73757Y795169D02*
Y803831D01*
X63243D01*
Y795169D01*
X73757D01*
G01X67807Y786500D02*
Y789600D01*
X68573D01*
X68880Y789445D01*
X69110Y789238D01*
X69302Y788928D01*
X69455Y788567D01*
X69493Y788050D01*
X69455Y787533D01*
X69302Y787172D01*
X69110Y786862D01*
X68880Y786655D01*
X68573Y786500D01*
X67807D01*
G01X71022Y789083D02*
X71252Y789393D01*
X71520Y789548D01*
X71827Y789600D01*
X72210Y789497D01*
X72478Y789238D01*
X72555Y788928D01*
X72517Y788618D01*
X72363Y788360D01*
X71597Y787843D01*
X71252Y787482D01*
X71022Y786965D01*
X70945Y786500D01*
X72555D01*
G01X74007Y786965D02*
X74237Y786707D01*
X74505Y786552D01*
X74850Y786500D01*
X75195Y786603D01*
X75463Y786810D01*
X75655Y787172D01*
X75693Y787585D01*
X75617Y787998D01*
X75425Y788257D01*
X75157Y788463D01*
X74888Y788515D01*
X74620Y788463D01*
X74275Y788257D01*
X74390Y789600D01*
X75425D01*
G01X77222Y787792D02*
X77490Y788153D01*
X77720Y788360D01*
X78027Y788463D01*
X78295Y788360D01*
X78487Y788153D01*
X78640Y787843D01*
X78678Y787482D01*
X78640Y787172D01*
X78487Y786862D01*
X78257Y786603D01*
X77988Y786500D01*
X77682Y786603D01*
X77413Y786913D01*
X77260Y787378D01*
X77222Y787895D01*
X77298Y788567D01*
X77413Y788928D01*
X77605Y789290D01*
X77873Y789548D01*
X78142Y789600D01*
X78410Y789497D01*
X78602Y789238D01*
G01X70073Y782514D02*
X70173Y785214D01*
Y782114D01*
G01X69780Y785386D02*
Y781842D01*
X76866D01*
Y785386D01*
X69858D01*
G01X78600Y805100D02*
Y798900D01*
X75400D01*
Y805100D01*
X78600D01*
G01X61943Y785364D02*
X68143D01*
Y782164D01*
X61943D01*
Y785364D01*
G01X55900Y796400D02*
Y802600D01*
X59100D01*
Y796400D01*
X55900D01*
G01X69227Y823500D02*
X66987D01*
G01X68200Y821875D02*
Y825125D01*
G01X61724Y825295D02*
Y829233D01*
X59756Y827264D01*
X61724Y825295D01*
G01X59362D02*
Y829233D01*
G01X70807Y810100D02*
Y807878D01*
X70960Y807413D01*
X71267Y807103D01*
X71650Y807000D01*
X72033Y807103D01*
X72340Y807413D01*
X72493Y807878D01*
Y810100D01*
G01X73907Y807620D02*
X74137Y807258D01*
X74443Y807052D01*
X74788Y807000D01*
X75095Y807052D01*
X75402Y807310D01*
X75593Y807620D01*
X75632Y807930D01*
X75555Y808292D01*
X75287Y808550D01*
X75018Y808653D01*
X74673D01*
G01X75018D02*
X75248Y808808D01*
X75440Y809067D01*
X75517Y809377D01*
X75440Y809687D01*
X75248Y809945D01*
X74903Y810100D01*
X74558Y810048D01*
X74213Y809842D01*
G01X77122Y808292D02*
X77390Y808653D01*
X77620Y808860D01*
X77927Y808963D01*
X78195Y808860D01*
X78387Y808653D01*
X78540Y808343D01*
X78578Y807982D01*
X78540Y807672D01*
X78387Y807362D01*
X78157Y807103D01*
X77888Y807000D01*
X77582Y807103D01*
X77313Y807413D01*
X77160Y807878D01*
X77122Y808395D01*
X77198Y809067D01*
X77313Y809428D01*
X77505Y809790D01*
X77773Y810048D01*
X78042Y810100D01*
X78310Y809997D01*
X78502Y809738D01*
G01X81410Y807000D02*
Y810100D01*
X79992Y807878D01*
X81908D01*
G01X73757Y811169D02*
Y819831D01*
X63243D01*
Y811169D01*
X73757D01*
G01X60773Y808500D02*
X63013D01*
G01X61800Y810125D02*
Y806875D01*
G01X65000Y822727D02*
Y820487D01*
G01X66625Y821700D02*
X63375D01*
G01X78600Y818100D02*
Y811900D01*
X75400D01*
Y818100D01*
X78600D01*
G01X76100Y821900D02*
X69900D01*
Y825100D01*
X76100D01*
Y821900D01*
G01X69600Y805900D02*
X63400D01*
Y809100D01*
X69600D01*
Y805900D01*
G01X61273Y838500D02*
X63513D01*
G01X62300Y840125D02*
Y836875D01*
G01X57087Y838500D02*
X59513D01*
G01X57116Y832664D02*
X57216Y835364D01*
Y832264D01*
G01X56823Y835536D02*
Y831992D01*
X63909D01*
Y835536D01*
X56901D01*
G01X72400Y835600D02*
X78600D01*
Y832400D01*
X72400D01*
Y835600D01*
G01X71600Y832400D02*
X65400D01*
Y835600D01*
X71600D01*
Y832400D01*
G01X77100Y851100D02*
Y844900D01*
X73900D01*
Y851100D01*
X77100D01*
G01X79100Y826200D02*
X68900D01*
Y830800D01*
X79100D01*
Y826200D01*
G01X77400Y860800D02*
X87600D01*
Y856200D01*
X77400D01*
Y860800D01*
G01X65669Y884900D02*
Y895669D01*
X60669Y900669D01*
G01X55961Y1012100D02*
X62161D01*
Y1008900D01*
X55961D01*
Y1012100D01*
G01X68661Y1010600D02*
Y1004400D01*
X65461D01*
Y1010600D01*
X68661D01*
G01X73192Y1032172D02*
X73292Y1032372D01*
X73392Y1032472D01*
X73542Y1032572D01*
X73742Y1032622D01*
X73992Y1032572D01*
X74242Y1032322D01*
X74292Y1032172D01*
Y1031822D01*
X74242Y1031672D01*
X74142Y1031522D01*
X74042Y1031422D01*
X73892Y1031322D01*
X73692Y1031172D01*
X73542Y1030972D01*
X73442Y1030872D01*
X73342Y1030722D01*
X73242Y1030422D01*
X73192Y1030072D01*
X74392D01*
G01X75342Y1031772D02*
Y1030072D01*
G01Y1031272D02*
X75442Y1031472D01*
X75542Y1031622D01*
X75642Y1031722D01*
X75842Y1031772D01*
X75992D01*
X76192Y1031722D01*
X76342Y1031522D01*
X76442Y1031322D01*
Y1030072D01*
G01X78802Y1030822D02*
G03I-710J0D01*
G01X78642Y1031272D02*
X78542Y1031372D01*
X78392Y1031472D01*
X78242Y1031522D01*
X77992D01*
X77792Y1031472D01*
X77642Y1031372D01*
X77492Y1031222D01*
X77442Y1031122D01*
X77392Y1030972D01*
Y1030772D01*
X77442Y1030522D01*
X77542Y1030372D01*
X77642Y1030272D01*
X77792Y1030172D01*
X77942Y1030122D01*
X78142D01*
X78392Y1030172D01*
X78542Y1030272D01*
X78642Y1030372D01*
G01X54900Y1021600D02*
X61100D01*
Y1018400D01*
X54900D01*
Y1021600D01*
G01X61100Y1022400D02*
X54900D01*
Y1025600D01*
X61100D01*
Y1022400D01*
G01Y1014400D02*
X54900D01*
Y1017600D01*
X61100D01*
Y1014400D01*
G01X61900Y1014900D02*
Y1021100D01*
X65100D01*
Y1014900D01*
X61900D01*
G01X93552Y1042222D02*
G03I-8010J0D01*
G01X67587Y1125500D02*
X70013D01*
G01X68307Y1121000D02*
Y1124100D01*
X69073D01*
X69380Y1123945D01*
X69610Y1123738D01*
X69802Y1123428D01*
X69955Y1123067D01*
X69993Y1122550D01*
X69955Y1122033D01*
X69802Y1121672D01*
X69610Y1121362D01*
X69380Y1121155D01*
X69073Y1121000D01*
X68307D01*
G01X71522Y1123583D02*
X71752Y1123893D01*
X72020Y1124048D01*
X72327Y1124100D01*
X72710Y1123997D01*
X72978Y1123738D01*
X73055Y1123428D01*
X73017Y1123118D01*
X72863Y1122860D01*
X72097Y1122343D01*
X71752Y1121982D01*
X71522Y1121465D01*
X71445Y1121000D01*
X73055D01*
G01X74622Y1122292D02*
X74890Y1122653D01*
X75120Y1122860D01*
X75427Y1122963D01*
X75695Y1122860D01*
X75887Y1122653D01*
X76040Y1122343D01*
X76078Y1121982D01*
X76040Y1121672D01*
X75887Y1121362D01*
X75657Y1121103D01*
X75388Y1121000D01*
X75082Y1121103D01*
X74813Y1121413D01*
X74660Y1121878D01*
X74622Y1122395D01*
X74698Y1123067D01*
X74813Y1123428D01*
X75005Y1123790D01*
X75273Y1124048D01*
X75542Y1124100D01*
X75810Y1123997D01*
X76002Y1123738D01*
G01X78450Y1121000D02*
Y1124100D01*
X77990Y1123480D01*
G01Y1121000D02*
X78910D01*
G01X69827Y1138300D02*
X67587D01*
G01X68800Y1136675D02*
Y1139925D01*
G01X61724Y1134181D02*
Y1138119D01*
X59756Y1136150D01*
X61724Y1134181D01*
G01X59362D02*
Y1138119D01*
G01X65498Y1142716D02*
X67738D01*
G01X66525Y1144341D02*
Y1141091D01*
G01X57116Y1141550D02*
X57216Y1144250D01*
Y1141150D01*
G01X56823Y1144422D02*
Y1140878D01*
X63909D01*
Y1144422D01*
X56901D01*
G01X70116Y1127550D02*
X70216Y1130250D01*
Y1127150D01*
G01X69823Y1130422D02*
Y1126878D01*
X76909D01*
Y1130422D01*
X69901D01*
G01X77773Y1147500D02*
X80013D01*
G01X78800Y1149125D02*
Y1145875D01*
G01X68087Y1150500D02*
X70513D01*
G01X70073Y1146400D02*
X70173Y1149100D01*
Y1146000D01*
G01X69780Y1149272D02*
Y1145728D01*
X76866D01*
Y1149272D01*
X69858D01*
G01X70443Y1144250D02*
X76643D01*
Y1141050D01*
X70443D01*
Y1144250D01*
G01X61943Y1149250D02*
X68143D01*
Y1146050D01*
X61943D01*
Y1149250D01*
G01X61443Y1130250D02*
X67643D01*
Y1127050D01*
X61443D01*
Y1130250D01*
G01X70400Y1140100D02*
X76600D01*
Y1136900D01*
X70400D01*
Y1140100D01*
G01X78600Y1131700D02*
X68400D01*
Y1136300D01*
X78600D01*
Y1131700D01*
G01X70307Y1170600D02*
Y1168378D01*
X70460Y1167913D01*
X70767Y1167603D01*
X71150Y1167500D01*
X71533Y1167603D01*
X71840Y1167913D01*
X71993Y1168378D01*
Y1170600D01*
G01X73407Y1168120D02*
X73637Y1167758D01*
X73943Y1167552D01*
X74288Y1167500D01*
X74595Y1167552D01*
X74902Y1167810D01*
X75093Y1168120D01*
X75132Y1168430D01*
X75055Y1168792D01*
X74787Y1169050D01*
X74518Y1169153D01*
X74173D01*
G01X74518D02*
X74748Y1169308D01*
X74940Y1169567D01*
X75017Y1169877D01*
X74940Y1170187D01*
X74748Y1170445D01*
X74403Y1170600D01*
X74058Y1170548D01*
X73713Y1170342D01*
G01X76622Y1168792D02*
X76890Y1169153D01*
X77120Y1169360D01*
X77427Y1169463D01*
X77695Y1169360D01*
X77887Y1169153D01*
X78040Y1168843D01*
X78078Y1168482D01*
X78040Y1168172D01*
X77887Y1167862D01*
X77657Y1167603D01*
X77388Y1167500D01*
X77082Y1167603D01*
X76813Y1167913D01*
X76660Y1168378D01*
X76622Y1168895D01*
X76698Y1169567D01*
X76813Y1169928D01*
X77005Y1170290D01*
X77273Y1170548D01*
X77542Y1170600D01*
X77810Y1170497D01*
X78002Y1170238D01*
G01X79722Y1168792D02*
X79990Y1169153D01*
X80220Y1169360D01*
X80527Y1169463D01*
X80795Y1169360D01*
X80987Y1169153D01*
X81140Y1168843D01*
X81178Y1168482D01*
X81140Y1168172D01*
X80987Y1167862D01*
X80757Y1167603D01*
X80488Y1167500D01*
X80182Y1167603D01*
X79913Y1167913D01*
X79760Y1168378D01*
X79722Y1168895D01*
X79798Y1169567D01*
X79913Y1169928D01*
X80105Y1170290D01*
X80373Y1170548D01*
X80642Y1170600D01*
X80910Y1170497D01*
X81102Y1170238D01*
G01X73257Y1171669D02*
Y1180331D01*
X62743D01*
Y1171669D01*
X73257D01*
G01Y1155669D02*
Y1164331D01*
X62743D01*
Y1155669D01*
X73257D01*
G01X59773Y1176100D02*
X62013D01*
G01X60800Y1177725D02*
Y1174475D01*
G01X65857Y1151660D02*
Y1154760D01*
X66623D01*
X66930Y1154605D01*
X67160Y1154398D01*
X67352Y1154088D01*
X67505Y1153727D01*
X67543Y1153210D01*
X67505Y1152693D01*
X67352Y1152332D01*
X67160Y1152022D01*
X66930Y1151815D01*
X66623Y1151660D01*
X65857D01*
G01X69072Y1154243D02*
X69302Y1154553D01*
X69570Y1154708D01*
X69877Y1154760D01*
X70260Y1154657D01*
X70528Y1154398D01*
X70605Y1154088D01*
X70567Y1153778D01*
X70413Y1153520D01*
X69647Y1153003D01*
X69302Y1152642D01*
X69072Y1152125D01*
X68995Y1151660D01*
X70605D01*
G01X72172Y1152952D02*
X72440Y1153313D01*
X72670Y1153520D01*
X72977Y1153623D01*
X73245Y1153520D01*
X73437Y1153313D01*
X73590Y1153003D01*
X73628Y1152642D01*
X73590Y1152332D01*
X73437Y1152022D01*
X73207Y1151763D01*
X72938Y1151660D01*
X72632Y1151763D01*
X72363Y1152073D01*
X72210Y1152538D01*
X72172Y1153055D01*
X72248Y1153727D01*
X72363Y1154088D01*
X72555Y1154450D01*
X72823Y1154708D01*
X73092Y1154760D01*
X73360Y1154657D01*
X73552Y1154398D01*
G01X75272Y1154243D02*
X75502Y1154553D01*
X75770Y1154708D01*
X76077Y1154760D01*
X76460Y1154657D01*
X76728Y1154398D01*
X76805Y1154088D01*
X76767Y1153778D01*
X76613Y1153520D01*
X75847Y1153003D01*
X75502Y1152642D01*
X75272Y1152125D01*
X75195Y1151660D01*
X76805D01*
G01X78100Y1162100D02*
Y1155900D01*
X74900D01*
Y1162100D01*
X78100D01*
G01Y1178100D02*
Y1171900D01*
X74900D01*
Y1178100D01*
X78100D01*
G01X69100Y1166400D02*
X62900D01*
Y1169600D01*
X69100D01*
Y1166400D01*
G01X68827Y1187200D02*
X66587D01*
G01X67800Y1185575D02*
Y1188825D01*
G01X61724Y1188681D02*
Y1192619D01*
X59756Y1190650D01*
X61724Y1188681D01*
G01X59362D02*
Y1192619D01*
G01X60903Y1181120D02*
X63143D01*
G01X61930Y1182745D02*
Y1179495D01*
G01X63400Y1195400D02*
Y1201600D01*
X66600D01*
Y1195400D01*
X63400D01*
G01X67900Y1198100D02*
X74100D01*
Y1194900D01*
X67900D01*
Y1198100D01*
G01X69100Y1182400D02*
X62900D01*
Y1185600D01*
X69100D01*
Y1182400D01*
G01X78600Y1188700D02*
X68400D01*
Y1193300D01*
X78600D01*
Y1188700D01*
G01X97600Y57800D02*
Y51600D01*
X94400D01*
Y57800D01*
X97600D01*
G01X93100D02*
Y51600D01*
X89900D01*
Y57800D01*
X93100D01*
G01X104100D02*
Y51600D01*
X100900D01*
Y57800D01*
X104100D01*
G01X97307Y68100D02*
Y65878D01*
X97460Y65413D01*
X97767Y65103D01*
X98150Y65000D01*
X98533Y65103D01*
X98840Y65413D01*
X98993Y65878D01*
Y68100D01*
G01X100407Y65620D02*
X100637Y65258D01*
X100943Y65052D01*
X101288Y65000D01*
X101595Y65052D01*
X101902Y65310D01*
X102093Y65620D01*
X102132Y65930D01*
X102055Y66292D01*
X101787Y66550D01*
X101518Y66653D01*
X101173D01*
G01X101518D02*
X101748Y66808D01*
X101940Y67067D01*
X102017Y67377D01*
X101940Y67687D01*
X101748Y67945D01*
X101403Y68100D01*
X101058Y68048D01*
X100713Y67842D01*
G01X103622Y67583D02*
X103852Y67893D01*
X104120Y68048D01*
X104427Y68100D01*
X104810Y67997D01*
X105078Y67738D01*
X105155Y67428D01*
X105117Y67118D01*
X104963Y66860D01*
X104197Y66343D01*
X103852Y65982D01*
X103622Y65465D01*
X103545Y65000D01*
X105155D01*
G01X106607Y65620D02*
X106837Y65258D01*
X107143Y65052D01*
X107488Y65000D01*
X107795Y65052D01*
X108102Y65310D01*
X108293Y65620D01*
X108332Y65930D01*
X108255Y66292D01*
X107987Y66550D01*
X107718Y66653D01*
X107373D01*
G01X107718D02*
X107948Y66808D01*
X108140Y67067D01*
X108217Y67377D01*
X108140Y67687D01*
X107948Y67945D01*
X107603Y68100D01*
X107258Y68048D01*
X106913Y67842D01*
G01X109057Y69469D02*
Y78531D01*
X96943D01*
Y69469D01*
X109057D01*
G01X80467Y80100D02*
Y83200D01*
X81233D01*
X81540Y83045D01*
X81770Y82838D01*
X81962Y82528D01*
X82115Y82167D01*
X82153Y81650D01*
X82115Y81133D01*
X81962Y80772D01*
X81770Y80462D01*
X81540Y80255D01*
X81233Y80100D01*
X80467D01*
G01X83682Y82683D02*
X83912Y82993D01*
X84180Y83148D01*
X84487Y83200D01*
X84870Y83097D01*
X85138Y82838D01*
X85215Y82528D01*
X85177Y82218D01*
X85023Y81960D01*
X84257Y81443D01*
X83912Y81082D01*
X83682Y80565D01*
X83605Y80100D01*
X85215D01*
G01X87970D02*
Y83200D01*
X86552Y80978D01*
X88468D01*
G01X91070Y80100D02*
Y83200D01*
X89652Y80978D01*
X91568D01*
G01X96400Y83151D02*
X102600D01*
Y79951D01*
X96400D01*
Y83151D01*
G01X97147Y109810D02*
Y107588D01*
X97300Y107123D01*
X97607Y106813D01*
X97990Y106710D01*
X98373Y106813D01*
X98680Y107123D01*
X98833Y107588D01*
Y109810D01*
G01X100362Y108002D02*
X100630Y108363D01*
X100860Y108570D01*
X101167Y108673D01*
X101435Y108570D01*
X101627Y108363D01*
X101780Y108053D01*
X101818Y107692D01*
X101780Y107382D01*
X101627Y107072D01*
X101397Y106813D01*
X101128Y106710D01*
X100822Y106813D01*
X100553Y107123D01*
X100400Y107588D01*
X100362Y108105D01*
X100438Y108777D01*
X100553Y109138D01*
X100745Y109500D01*
X101013Y109758D01*
X101282Y109810D01*
X101550Y109707D01*
X101742Y109448D01*
G01X104113Y106710D02*
X104190Y107382D01*
X104305Y107950D01*
X104458Y108467D01*
X104650Y109035D01*
X104957Y109810D01*
X103423D01*
G01X94943Y105531D02*
Y96469D01*
X107057D01*
Y105531D01*
X94943D01*
G01X79900Y98307D02*
X82122D01*
X82587Y98460D01*
X82897Y98767D01*
X83000Y99150D01*
X82897Y99533D01*
X82587Y99840D01*
X82122Y99993D01*
X79900D01*
G01X81708Y101522D02*
X81347Y101790D01*
X81140Y102020D01*
X81037Y102327D01*
X81140Y102595D01*
X81347Y102787D01*
X81657Y102940D01*
X82018Y102978D01*
X82328Y102940D01*
X82638Y102787D01*
X82897Y102557D01*
X83000Y102288D01*
X82897Y101982D01*
X82587Y101713D01*
X82122Y101560D01*
X81605Y101522D01*
X80933Y101598D01*
X80572Y101713D01*
X80210Y101905D01*
X79952Y102173D01*
X79900Y102442D01*
X80003Y102710D01*
X80262Y102902D01*
G01X81708Y104622D02*
X81347Y104890D01*
X81140Y105120D01*
X81037Y105427D01*
X81140Y105695D01*
X81347Y105887D01*
X81657Y106040D01*
X82018Y106078D01*
X82328Y106040D01*
X82638Y105887D01*
X82897Y105657D01*
X83000Y105388D01*
X82897Y105082D01*
X82587Y104813D01*
X82122Y104660D01*
X81605Y104622D01*
X80933Y104698D01*
X80572Y104813D01*
X80210Y105005D01*
X79952Y105273D01*
X79900Y105542D01*
X80003Y105810D01*
X80262Y106002D01*
G01X85941Y101000D02*
X84169Y102500D01*
Y106240D01*
X92831D01*
Y95760D01*
X84169D01*
Y99500D01*
X85941Y101000D01*
G01X93100Y90400D02*
X86900D01*
Y93600D01*
X93100D01*
Y90400D01*
G01Y114100D02*
Y107900D01*
X89900D01*
Y114100D01*
X93100D01*
G01X83900Y107900D02*
Y114100D01*
X87100D01*
Y107900D01*
X83900D01*
G01X86107Y118340D02*
Y116118D01*
X86260Y115653D01*
X86567Y115343D01*
X86950Y115240D01*
X87333Y115343D01*
X87640Y115653D01*
X87793Y116118D01*
Y118340D01*
G01X90510Y115240D02*
Y118340D01*
X89092Y116118D01*
X91008D01*
G01X93150Y118340D02*
X92843Y118237D01*
X92613Y117978D01*
X92460Y117668D01*
X92345Y117255D01*
X92307Y116790D01*
X92345Y116325D01*
X92460Y115912D01*
X92613Y115602D01*
X92843Y115343D01*
X93150Y115240D01*
X93457Y115343D01*
X93687Y115602D01*
X93840Y115912D01*
X93955Y116325D01*
X93993Y116790D01*
X93955Y117255D01*
X93840Y117668D01*
X93687Y117978D01*
X93457Y118237D01*
X93150Y118340D01*
G01X95598Y115602D02*
X95867Y115343D01*
X96173Y115240D01*
X96480Y115343D01*
X96748Y115653D01*
X96940Y116118D01*
X97017Y116583D01*
Y117152D01*
X96940Y117617D01*
X96748Y118030D01*
X96518Y118237D01*
X96250Y118340D01*
X95943Y118237D01*
X95713Y118030D01*
X95560Y117720D01*
X95483Y117307D01*
X95560Y116945D01*
X95752Y116583D01*
X95982Y116377D01*
X96250Y116325D01*
X96557Y116428D01*
X96787Y116687D01*
X97017Y117152D01*
G01X96757Y119169D02*
Y127831D01*
X86243D01*
Y119169D01*
X96757D01*
G01X98400Y117900D02*
Y124100D01*
X101600D01*
Y117900D01*
X98400D01*
G01X89100Y137600D02*
Y131400D01*
X85900D01*
Y137600D01*
X89100D01*
G01X80000Y118900D02*
Y129100D01*
X84600D01*
Y118900D01*
X80000D01*
G01X86417Y220437D02*
Y223537D01*
G01X88027D02*
Y220437D01*
G01Y221987D02*
X86417D01*
G01X90322Y220437D02*
Y223537D01*
X89862Y222917D01*
G01Y220437D02*
X90782D01*
G01X106057Y406469D02*
Y415531D01*
X93943D01*
Y406469D01*
X106057D01*
G01X94307Y420100D02*
Y417878D01*
X94460Y417413D01*
X94767Y417103D01*
X95150Y417000D01*
X95533Y417103D01*
X95840Y417413D01*
X95993Y417878D01*
Y420100D01*
G01X97407Y417620D02*
X97637Y417258D01*
X97943Y417052D01*
X98288Y417000D01*
X98595Y417052D01*
X98902Y417310D01*
X99093Y417620D01*
X99132Y417930D01*
X99055Y418292D01*
X98787Y418550D01*
X98518Y418653D01*
X98173D01*
G01X98518D02*
X98748Y418808D01*
X98940Y419067D01*
X99017Y419377D01*
X98940Y419687D01*
X98748Y419945D01*
X98403Y420100D01*
X98058Y420048D01*
X97713Y419842D01*
G01X100622Y419583D02*
X100852Y419893D01*
X101120Y420048D01*
X101427Y420100D01*
X101810Y419997D01*
X102078Y419738D01*
X102155Y419428D01*
X102117Y419118D01*
X101963Y418860D01*
X101197Y418343D01*
X100852Y417982D01*
X100622Y417465D01*
X100545Y417000D01*
X102155D01*
G01X103607Y417465D02*
X103837Y417207D01*
X104105Y417052D01*
X104450Y417000D01*
X104795Y417103D01*
X105063Y417310D01*
X105255Y417672D01*
X105293Y418085D01*
X105217Y418498D01*
X105025Y418757D01*
X104757Y418963D01*
X104488Y419015D01*
X104220Y418963D01*
X103875Y418757D01*
X103990Y420100D01*
X105025D01*
G01X79307Y425000D02*
Y428100D01*
X80073D01*
X80380Y427945D01*
X80610Y427738D01*
X80802Y427428D01*
X80955Y427067D01*
X80993Y426550D01*
X80955Y426033D01*
X80802Y425672D01*
X80610Y425362D01*
X80380Y425155D01*
X80073Y425000D01*
X79307D01*
G01X82522Y427583D02*
X82752Y427893D01*
X83020Y428048D01*
X83327Y428100D01*
X83710Y427997D01*
X83978Y427738D01*
X84055Y427428D01*
X84017Y427118D01*
X83863Y426860D01*
X83097Y426343D01*
X82752Y425982D01*
X82522Y425465D01*
X82445Y425000D01*
X84055D01*
G01X85507Y425465D02*
X85737Y425207D01*
X86005Y425052D01*
X86350Y425000D01*
X86695Y425103D01*
X86963Y425310D01*
X87155Y425672D01*
X87193Y426085D01*
X87117Y426498D01*
X86925Y426757D01*
X86657Y426963D01*
X86388Y427015D01*
X86120Y426963D01*
X85775Y426757D01*
X85890Y428100D01*
X86925D01*
G01X89450D02*
X89143Y427997D01*
X88913Y427738D01*
X88760Y427428D01*
X88645Y427015D01*
X88607Y426550D01*
X88645Y426085D01*
X88760Y425672D01*
X88913Y425362D01*
X89143Y425103D01*
X89450Y425000D01*
X89757Y425103D01*
X89987Y425362D01*
X90140Y425672D01*
X90255Y426085D01*
X90293Y426550D01*
X90255Y427015D01*
X90140Y427428D01*
X89987Y427738D01*
X89757Y427997D01*
X89450Y428100D01*
G01X98007Y453600D02*
Y451378D01*
X98160Y450913D01*
X98467Y450603D01*
X98850Y450500D01*
X99233Y450603D01*
X99540Y450913D01*
X99693Y451378D01*
Y453600D01*
G01X101222Y451792D02*
X101490Y452153D01*
X101720Y452360D01*
X102027Y452463D01*
X102295Y452360D01*
X102487Y452153D01*
X102640Y451843D01*
X102678Y451482D01*
X102640Y451172D01*
X102487Y450862D01*
X102257Y450603D01*
X101988Y450500D01*
X101682Y450603D01*
X101413Y450913D01*
X101260Y451378D01*
X101222Y451895D01*
X101298Y452567D01*
X101413Y452928D01*
X101605Y453290D01*
X101873Y453548D01*
X102142Y453600D01*
X102410Y453497D01*
X102602Y453238D01*
G01X104207Y450965D02*
X104437Y450707D01*
X104705Y450552D01*
X105050Y450500D01*
X105395Y450603D01*
X105663Y450810D01*
X105855Y451172D01*
X105893Y451585D01*
X105817Y451998D01*
X105625Y452257D01*
X105357Y452463D01*
X105088Y452515D01*
X104820Y452463D01*
X104475Y452257D01*
X104590Y453600D01*
X105625D01*
G01X97443Y464531D02*
Y455469D01*
X109557D01*
Y464531D01*
X97443D01*
G01X85941Y459000D02*
X84169Y460500D01*
Y464240D01*
X92831D01*
Y453760D01*
X84169D01*
Y457500D01*
X85941Y459000D01*
G01X83900Y452100D02*
X90100D01*
Y448900D01*
X83900D01*
Y452100D01*
G01X79400Y460307D02*
X81622D01*
X82087Y460460D01*
X82397Y460767D01*
X82500Y461150D01*
X82397Y461533D01*
X82087Y461840D01*
X81622Y461993D01*
X79400D01*
G01X81208Y463522D02*
X80847Y463790D01*
X80640Y464020D01*
X80537Y464327D01*
X80640Y464595D01*
X80847Y464787D01*
X81157Y464940D01*
X81518Y464978D01*
X81828Y464940D01*
X82138Y464787D01*
X82397Y464557D01*
X82500Y464288D01*
X82397Y463982D01*
X82087Y463713D01*
X81622Y463560D01*
X81105Y463522D01*
X80433Y463598D01*
X80072Y463713D01*
X79710Y463905D01*
X79452Y464173D01*
X79400Y464442D01*
X79503Y464710D01*
X79762Y464902D01*
G01X82500Y467810D02*
X79400D01*
X81622Y466392D01*
Y468308D01*
G01X103600Y476900D02*
X97400D01*
Y480100D01*
X103600D01*
Y476900D01*
G01X93100Y472100D02*
Y465900D01*
X89900D01*
Y472100D01*
X93100D01*
G01X83900Y465900D02*
Y472100D01*
X87100D01*
Y465900D01*
X83900D01*
G01X94025Y502632D02*
X94275Y502472D01*
X94400Y502285D01*
X94442Y502072D01*
X94359Y501805D01*
X94150Y501618D01*
X93900Y501565D01*
X93650Y501592D01*
X93442Y501698D01*
X93025Y502232D01*
X92734Y502472D01*
X92317Y502632D01*
X91942Y502685D01*
Y501565D01*
G01X94025Y500432D02*
X94275Y500272D01*
X94400Y500085D01*
X94442Y499872D01*
X94359Y499605D01*
X94150Y499418D01*
X93900Y499365D01*
X93650Y499392D01*
X93442Y499498D01*
X93025Y500032D01*
X92734Y500272D01*
X92317Y500432D01*
X91942Y500485D01*
Y499365D01*
G01X88243Y499150D02*
X88403Y499400D01*
X88590Y499525D01*
X88803Y499567D01*
X89070Y499484D01*
X89257Y499275D01*
X89310Y499025D01*
X89283Y498775D01*
X89177Y498567D01*
X88643Y498150D01*
X88403Y497859D01*
X88243Y497442D01*
X88190Y497067D01*
X89310D01*
G01X90950D02*
Y499567D01*
X90630Y499067D01*
G01Y497067D02*
X91270D01*
G01X85700Y495500D02*
Y498500D01*
G01X88074Y500429D02*
X90571D01*
Y502915D01*
G01X103600Y481825D02*
X97400D01*
Y485025D01*
X103600D01*
Y481825D01*
G01Y496900D02*
X97400D01*
Y500100D01*
X103600D01*
Y496900D01*
G01Y486900D02*
X97400D01*
Y490100D01*
X103600D01*
Y486900D01*
G01X97400Y505100D02*
X103600D01*
Y501900D01*
X97400D01*
Y505100D01*
G01Y495100D02*
X103600D01*
Y491900D01*
X97400D01*
Y495100D01*
G01X85900Y482400D02*
Y488600D01*
X89100D01*
Y482400D01*
X85900D01*
G01X93600Y517582D02*
X93850Y517422D01*
X93975Y517235D01*
X94017Y517022D01*
X93934Y516755D01*
X93725Y516568D01*
X93475Y516515D01*
X93225Y516542D01*
X93017Y516648D01*
X92600Y517182D01*
X92309Y517422D01*
X91892Y517582D01*
X91517Y517635D01*
Y516515D01*
G01Y514875D02*
X91559Y514688D01*
X91684Y514475D01*
X91892Y514342D01*
X92184Y514288D01*
X92475Y514342D01*
X92725Y514502D01*
X92850Y514742D01*
Y515008D01*
X92934Y515168D01*
X93142Y515302D01*
X93434Y515355D01*
X93725Y515275D01*
X93934Y515088D01*
X94017Y514875D01*
X93934Y514662D01*
X93725Y514475D01*
X93434Y514395D01*
X93142Y514448D01*
X92934Y514582D01*
X92850Y514742D01*
Y515008D01*
X92725Y515248D01*
X92475Y515408D01*
X92184Y515462D01*
X91892Y515408D01*
X91684Y515275D01*
X91559Y515062D01*
X91517Y514875D01*
G01X94500Y508500D02*
X92500D01*
G01X80932Y518520D02*
Y520520D01*
G01X90571Y514105D02*
Y516571D01*
X88100D01*
G01X91400Y524400D02*
Y530600D01*
X94600D01*
Y524400D01*
X91400D01*
G01X85900D02*
Y530600D01*
X89100D01*
Y524400D01*
X85900D01*
G01X97400Y511100D02*
X103600D01*
Y507900D01*
X97400D01*
Y511100D01*
G01Y523100D02*
X103600D01*
Y519900D01*
X97400D01*
Y523100D01*
G01X103600Y515900D02*
X97400D01*
Y519100D01*
X103600D01*
Y515900D01*
G01X83600Y530600D02*
Y524400D01*
X80400D01*
Y530600D01*
X83600D01*
G01X94600Y538600D02*
Y532400D01*
X91400D01*
Y538600D01*
X94600D01*
G01X89100D02*
Y532400D01*
X85900D01*
Y538600D01*
X89100D01*
G01X83600D02*
Y532400D01*
X80400D01*
Y538600D01*
X83600D01*
G01X97400Y533100D02*
X103600D01*
Y529900D01*
X97400D01*
Y533100D01*
G01Y528600D02*
X103600D01*
Y525400D01*
X97400D01*
Y528600D01*
G01X102600Y560600D02*
Y554400D01*
X99400D01*
Y560600D01*
X102600D01*
G01X92600D02*
Y554400D01*
X89400D01*
Y560600D01*
X92600D01*
G01X97100D02*
Y554400D01*
X93900D01*
Y560600D01*
X97100D01*
G01X81600D02*
Y554400D01*
X78400D01*
Y560600D01*
X81600D01*
G01X94600Y569600D02*
Y563400D01*
X91400D01*
Y569600D01*
X94600D01*
G01X102600D02*
Y563400D01*
X99400D01*
Y569600D01*
X102600D01*
G01X86600D02*
Y563400D01*
X83400D01*
Y569600D01*
X86600D01*
G01X78400Y563400D02*
Y569600D01*
X81600D01*
Y563400D01*
X78400D01*
G01X81900Y606400D02*
X113100D01*
Y590600D01*
X81900D01*
Y596200D01*
X84200Y598500D01*
X81900Y600800D01*
Y606400D01*
G01X82400Y644600D02*
Y638400D01*
X79200D01*
Y644600D01*
X82400D01*
G01X82500Y633100D02*
Y626900D01*
X79300D01*
Y633100D01*
X82500D01*
G01X90900Y638400D02*
Y644600D01*
X94100D01*
Y638400D01*
X90900D01*
G01X83100D02*
Y644600D01*
X86300D01*
Y638400D01*
X83100D01*
G01X96900D02*
Y644600D01*
X100100D01*
Y638400D01*
X96900D01*
G01X89400Y626900D02*
Y633100D01*
X92600D01*
Y626900D01*
X89400D01*
G01X85400D02*
Y633100D01*
X88600D01*
Y626900D01*
X85400D01*
G01X96900D02*
Y633100D01*
X100100D01*
Y626900D01*
X96900D01*
G01X85100Y674400D02*
X78900D01*
Y677600D01*
X85100D01*
Y674400D01*
G01Y682400D02*
X78900D01*
Y685600D01*
X85100D01*
Y682400D01*
G01X78900Y673600D02*
X85100D01*
Y670400D01*
X78900D01*
Y673600D01*
G01Y681600D02*
X85100D01*
Y678400D01*
X78900D01*
Y681600D01*
G01Y689600D02*
X85100D01*
Y686400D01*
X78900D01*
Y689600D01*
G01X85100Y690400D02*
X78900D01*
Y693600D01*
X85100D01*
Y690400D01*
G01Y698400D02*
X78900D01*
Y701600D01*
X85100D01*
Y698400D01*
G01X78900Y697600D02*
X85100D01*
Y694400D01*
X78900D01*
Y697600D01*
G01Y705600D02*
X85100D01*
Y702400D01*
X78900D01*
Y705600D01*
G01Y711100D02*
X85100D01*
Y707900D01*
X78900D01*
Y711100D01*
G01X103600Y704900D02*
X97400D01*
Y708100D01*
X103600D01*
Y704900D01*
G01Y709400D02*
X97400D01*
Y712600D01*
X103600D01*
Y709400D01*
G01X78900Y716600D02*
X85100D01*
Y713400D01*
X78900D01*
Y716600D01*
G01X100100Y729400D02*
X93900D01*
Y732600D01*
X100100D01*
Y729400D01*
G01Y736400D02*
X93900D01*
Y739600D01*
X100100D01*
Y736400D01*
G01Y743400D02*
X93900D01*
Y746600D01*
X100100D01*
Y743400D01*
G01X94307Y770100D02*
Y767878D01*
X94460Y767413D01*
X94767Y767103D01*
X95150Y767000D01*
X95533Y767103D01*
X95840Y767413D01*
X95993Y767878D01*
Y770100D01*
G01X97407Y767620D02*
X97637Y767258D01*
X97943Y767052D01*
X98288Y767000D01*
X98595Y767052D01*
X98902Y767310D01*
X99093Y767620D01*
X99132Y767930D01*
X99055Y768292D01*
X98787Y768550D01*
X98518Y768653D01*
X98173D01*
G01X98518D02*
X98748Y768808D01*
X98940Y769067D01*
X99017Y769377D01*
X98940Y769687D01*
X98748Y769945D01*
X98403Y770100D01*
X98058Y770048D01*
X97713Y769842D01*
G01X100622Y769583D02*
X100852Y769893D01*
X101120Y770048D01*
X101427Y770100D01*
X101810Y769997D01*
X102078Y769738D01*
X102155Y769428D01*
X102117Y769118D01*
X101963Y768860D01*
X101197Y768343D01*
X100852Y767982D01*
X100622Y767465D01*
X100545Y767000D01*
X102155D01*
G01X104373D02*
X104450Y767672D01*
X104565Y768240D01*
X104718Y768757D01*
X104910Y769325D01*
X105217Y770100D01*
X103683D01*
G01X105557Y771469D02*
Y780531D01*
X93443D01*
Y771469D01*
X105557D01*
G01X95443Y826531D02*
Y817469D01*
X107557D01*
Y826531D01*
X95443D01*
G01X79400Y824807D02*
X81622D01*
X82087Y824960D01*
X82397Y825267D01*
X82500Y825650D01*
X82397Y826033D01*
X82087Y826340D01*
X81622Y826493D01*
X79400D01*
G01X81208Y828022D02*
X80847Y828290D01*
X80640Y828520D01*
X80537Y828827D01*
X80640Y829095D01*
X80847Y829287D01*
X81157Y829440D01*
X81518Y829478D01*
X81828Y829440D01*
X82138Y829287D01*
X82397Y829057D01*
X82500Y828788D01*
X82397Y828482D01*
X82087Y828213D01*
X81622Y828060D01*
X81105Y828022D01*
X80433Y828098D01*
X80072Y828213D01*
X79710Y828405D01*
X79452Y828673D01*
X79400Y828942D01*
X79503Y829210D01*
X79762Y829402D01*
G01X79917Y831122D02*
X79607Y831352D01*
X79452Y831620D01*
X79400Y831927D01*
X79503Y832310D01*
X79762Y832578D01*
X80072Y832655D01*
X80382Y832617D01*
X80640Y832463D01*
X81157Y831697D01*
X81518Y831352D01*
X82035Y831122D01*
X82500Y831045D01*
Y832655D01*
G01X85941Y822000D02*
X84169Y823500D01*
Y827240D01*
X92831D01*
Y816760D01*
X84169D01*
Y820500D01*
X85941Y822000D01*
G01X86900Y808900D02*
Y815100D01*
X90100D01*
Y808900D01*
X86900D01*
G01X97337Y831510D02*
Y829288D01*
X97490Y828823D01*
X97797Y828513D01*
X98180Y828410D01*
X98563Y828513D01*
X98870Y828823D01*
X99023Y829288D01*
Y831510D01*
G01X100552Y829702D02*
X100820Y830063D01*
X101050Y830270D01*
X101357Y830373D01*
X101625Y830270D01*
X101817Y830063D01*
X101970Y829753D01*
X102008Y829392D01*
X101970Y829082D01*
X101817Y828772D01*
X101587Y828513D01*
X101318Y828410D01*
X101012Y828513D01*
X100743Y828823D01*
X100590Y829288D01*
X100552Y829805D01*
X100628Y830477D01*
X100743Y830838D01*
X100935Y831200D01*
X101203Y831458D01*
X101472Y831510D01*
X101740Y831407D01*
X101932Y831148D01*
G01X103537Y829030D02*
X103767Y828668D01*
X104073Y828462D01*
X104418Y828410D01*
X104725Y828462D01*
X105032Y828720D01*
X105223Y829030D01*
X105262Y829340D01*
X105185Y829702D01*
X104917Y829960D01*
X104648Y830063D01*
X104303D01*
G01X104648D02*
X104878Y830218D01*
X105070Y830477D01*
X105147Y830787D01*
X105070Y831097D01*
X104878Y831355D01*
X104533Y831510D01*
X104188Y831458D01*
X103843Y831252D01*
G01X78777Y842980D02*
Y840758D01*
X78930Y840293D01*
X79237Y839983D01*
X79620Y839880D01*
X80003Y839983D01*
X80310Y840293D01*
X80463Y840758D01*
Y842980D01*
G01X83180Y839880D02*
Y842980D01*
X81762Y840758D01*
X83678D01*
G01X85820Y839880D02*
Y842980D01*
X85360Y842360D01*
G01Y839880D02*
X86280D01*
G01X88920D02*
Y842980D01*
X88460Y842360D01*
G01Y839880D02*
X89380D01*
G01X89257Y844169D02*
Y852831D01*
X78743D01*
Y844169D01*
X89257D01*
G01X93100Y835100D02*
Y828900D01*
X89900D01*
Y835100D01*
X93100D01*
G01X90900Y844400D02*
Y850600D01*
X94100D01*
Y844400D01*
X90900D01*
G01X83900Y828900D02*
Y835100D01*
X87100D01*
Y828900D01*
X83900D01*
G01X86417Y968468D02*
Y971568D01*
G01X88027D02*
Y968468D01*
G01Y970018D02*
X86417D01*
G01X89594Y971051D02*
X89824Y971361D01*
X90092Y971516D01*
X90399Y971568D01*
X90782Y971465D01*
X91050Y971206D01*
X91127Y970896D01*
X91089Y970586D01*
X90935Y970328D01*
X90169Y969811D01*
X89824Y969450D01*
X89594Y968933D01*
X89517Y968468D01*
X91127D01*
G01X91742Y1023222D02*
G02X84942Y1018222I-6035J1083D01*
G01X85042Y1028422D02*
G02X91742Y1023222I585J-6163D01*
G01X86042Y1028422D02*
G03X79342Y1023222I-585J-6163D01*
G01D02*
G03X86142Y1018222I6035J1083D01*
G01X78642Y1032622D02*
Y1030072D01*
G01X80992Y1032672D02*
Y1030072D01*
G01X82492Y1031772D02*
X83192Y1030072D01*
X83892Y1031772D01*
G01X85392Y1032672D02*
Y1030072D01*
G01X88292Y1031822D02*
Y1030072D01*
G01Y1033072D02*
X88192Y1032972D01*
Y1032872D01*
X88292Y1032772D01*
X88392Y1032872D01*
Y1032972D01*
X88292Y1033072D01*
G01X90042Y1031272D02*
X90142Y1031472D01*
X90242Y1031622D01*
X90342Y1031722D01*
X90542Y1031772D01*
X90692D01*
X90892Y1031722D01*
X91042Y1031522D01*
X91142Y1031322D01*
Y1030072D01*
G01X90042Y1031772D02*
Y1030072D01*
G01X92242Y1031722D02*
X93142D01*
G01X92692Y1032572D02*
Y1030072D01*
X93392Y1030122D01*
G01X95392Y1031672D02*
X95242Y1031722D01*
X95042Y1031772D01*
X94892D01*
X94692Y1031722D01*
X94592Y1031672D01*
X94442Y1031572D01*
X94342Y1031472D01*
X94242Y1031322D01*
X94192Y1031222D01*
X94142Y1030972D01*
Y1030822D01*
X94192Y1030622D01*
X94242Y1030522D01*
X94342Y1030372D01*
X94442Y1030272D01*
X94592Y1030172D01*
X94692Y1030122D01*
X94942Y1030072D01*
X95142D01*
X95392Y1030172D01*
G01X97092Y1032572D02*
Y1030072D01*
X97792Y1030122D01*
G01X96642Y1031722D02*
X97542D01*
G01X80342Y1048222D02*
X91342Y1036722D01*
G01X79773Y1128500D02*
X82013D01*
G01X80800Y1130125D02*
Y1126875D01*
G01X95457Y1148110D02*
Y1145888D01*
X95610Y1145423D01*
X95917Y1145113D01*
X96300Y1145010D01*
X96683Y1145113D01*
X96990Y1145423D01*
X97143Y1145888D01*
Y1148110D01*
G01X98557Y1145630D02*
X98787Y1145268D01*
X99093Y1145062D01*
X99438Y1145010D01*
X99745Y1145062D01*
X100052Y1145320D01*
X100243Y1145630D01*
X100282Y1145940D01*
X100205Y1146302D01*
X99937Y1146560D01*
X99668Y1146663D01*
X99323D01*
G01X99668D02*
X99898Y1146818D01*
X100090Y1147077D01*
X100167Y1147387D01*
X100090Y1147697D01*
X99898Y1147955D01*
X99553Y1148110D01*
X99208Y1148058D01*
X98863Y1147852D01*
G01X101772Y1147593D02*
X102002Y1147903D01*
X102270Y1148058D01*
X102577Y1148110D01*
X102960Y1148007D01*
X103228Y1147748D01*
X103305Y1147438D01*
X103267Y1147128D01*
X103113Y1146870D01*
X102347Y1146353D01*
X102002Y1145992D01*
X101772Y1145475D01*
X101695Y1145010D01*
X103305D01*
G01X104948Y1145372D02*
X105217Y1145113D01*
X105523Y1145010D01*
X105830Y1145113D01*
X106098Y1145423D01*
X106290Y1145888D01*
X106367Y1146353D01*
Y1146922D01*
X106290Y1147387D01*
X106098Y1147800D01*
X105868Y1148007D01*
X105600Y1148110D01*
X105293Y1148007D01*
X105063Y1147800D01*
X104910Y1147490D01*
X104833Y1147077D01*
X104910Y1146715D01*
X105102Y1146353D01*
X105332Y1146147D01*
X105600Y1146095D01*
X105907Y1146198D01*
X106137Y1146457D01*
X106367Y1146922D01*
G01X107557Y1134969D02*
Y1144031D01*
X95443D01*
Y1134969D01*
X107557D01*
G01X78807Y1166100D02*
Y1163878D01*
X78960Y1163413D01*
X79267Y1163103D01*
X79650Y1163000D01*
X80033Y1163103D01*
X80340Y1163413D01*
X80493Y1163878D01*
Y1166100D01*
G01X81907Y1163620D02*
X82137Y1163258D01*
X82443Y1163052D01*
X82788Y1163000D01*
X83095Y1163052D01*
X83402Y1163310D01*
X83593Y1163620D01*
X83632Y1163930D01*
X83555Y1164292D01*
X83287Y1164550D01*
X83018Y1164653D01*
X82673D01*
G01X83018D02*
X83248Y1164808D01*
X83440Y1165067D01*
X83517Y1165377D01*
X83440Y1165687D01*
X83248Y1165945D01*
X82903Y1166100D01*
X82558Y1166048D01*
X82213Y1165842D01*
G01X85122Y1164292D02*
X85390Y1164653D01*
X85620Y1164860D01*
X85927Y1164963D01*
X86195Y1164860D01*
X86387Y1164653D01*
X86540Y1164343D01*
X86578Y1163982D01*
X86540Y1163672D01*
X86387Y1163362D01*
X86157Y1163103D01*
X85888Y1163000D01*
X85582Y1163103D01*
X85313Y1163413D01*
X85160Y1163878D01*
X85122Y1164395D01*
X85198Y1165067D01*
X85313Y1165428D01*
X85505Y1165790D01*
X85773Y1166048D01*
X86042Y1166100D01*
X86310Y1165997D01*
X86502Y1165738D01*
G01X88873Y1163000D02*
X88950Y1163672D01*
X89065Y1164240D01*
X89218Y1164757D01*
X89410Y1165325D01*
X89717Y1166100D01*
X88183D01*
G01X86900Y1171900D02*
Y1178100D01*
X90100D01*
Y1171900D01*
X86900D01*
G01X97837Y1179030D02*
Y1176808D01*
X97990Y1176343D01*
X98297Y1176033D01*
X98680Y1175930D01*
X99063Y1176033D01*
X99370Y1176343D01*
X99523Y1176808D01*
Y1179030D01*
G01X101052Y1177222D02*
X101320Y1177583D01*
X101550Y1177790D01*
X101857Y1177893D01*
X102125Y1177790D01*
X102317Y1177583D01*
X102470Y1177273D01*
X102508Y1176912D01*
X102470Y1176602D01*
X102317Y1176292D01*
X102087Y1176033D01*
X101818Y1175930D01*
X101512Y1176033D01*
X101243Y1176343D01*
X101090Y1176808D01*
X101052Y1177325D01*
X101128Y1177997D01*
X101243Y1178358D01*
X101435Y1178720D01*
X101703Y1178978D01*
X101972Y1179030D01*
X102240Y1178927D01*
X102432Y1178668D01*
G01X104880Y1175930D02*
Y1179030D01*
X104420Y1178410D01*
G01Y1175930D02*
X105340D01*
G01X95443Y1189531D02*
Y1180469D01*
X107557D01*
Y1189531D01*
X95443D01*
G01X79400Y1184307D02*
X81622D01*
X82087Y1184460D01*
X82397Y1184767D01*
X82500Y1185150D01*
X82397Y1185533D01*
X82087Y1185840D01*
X81622Y1185993D01*
X79400D01*
G01X81208Y1187522D02*
X80847Y1187790D01*
X80640Y1188020D01*
X80537Y1188327D01*
X80640Y1188595D01*
X80847Y1188787D01*
X81157Y1188940D01*
X81518Y1188978D01*
X81828Y1188940D01*
X82138Y1188787D01*
X82397Y1188557D01*
X82500Y1188288D01*
X82397Y1187982D01*
X82087Y1187713D01*
X81622Y1187560D01*
X81105Y1187522D01*
X80433Y1187598D01*
X80072Y1187713D01*
X79710Y1187905D01*
X79452Y1188173D01*
X79400Y1188442D01*
X79503Y1188710D01*
X79762Y1188902D01*
G01X79400Y1191350D02*
X79503Y1191043D01*
X79762Y1190813D01*
X80072Y1190660D01*
X80485Y1190545D01*
X80950Y1190507D01*
X81415Y1190545D01*
X81828Y1190660D01*
X82138Y1190813D01*
X82397Y1191043D01*
X82500Y1191350D01*
X82397Y1191657D01*
X82138Y1191887D01*
X81828Y1192040D01*
X81415Y1192155D01*
X80950Y1192193D01*
X80485Y1192155D01*
X80072Y1192040D01*
X79762Y1191887D01*
X79503Y1191657D01*
X79400Y1191350D01*
G01X85941Y1185000D02*
X84169Y1186500D01*
Y1190240D01*
X92831D01*
Y1179760D01*
X84169D01*
Y1183500D01*
X85941Y1185000D01*
G01X93100Y1198100D02*
Y1191900D01*
X89900D01*
Y1198100D01*
X93100D01*
G01X83900Y1191900D02*
Y1198100D01*
X87100D01*
Y1191900D01*
X83900D01*
G01X97845Y1308145D02*
Y1311245D01*
G01X99455D02*
Y1308145D01*
G01Y1309695D02*
X97845D01*
G01X101750Y1308145D02*
Y1311245D01*
X101290Y1310625D01*
G01Y1308145D02*
X102210D01*
G01X104850D02*
Y1311245D01*
X104390Y1310625D01*
G01Y1308145D02*
X105310D01*
G01X108799Y6634D02*
X114055Y1378D01*
X123386D01*
X129292Y7283D01*
Y44685D01*
G01X108100Y57800D02*
Y51600D01*
X104900D01*
Y57800D01*
X108100D01*
G01X121300Y70007D02*
X123522D01*
X123987Y70160D01*
X124297Y70467D01*
X124400Y70850D01*
X124297Y71233D01*
X123987Y71540D01*
X123522Y71693D01*
X121300D01*
G01X123780Y73107D02*
X124142Y73337D01*
X124348Y73643D01*
X124400Y73988D01*
X124348Y74295D01*
X124090Y74602D01*
X123780Y74793D01*
X123470Y74832D01*
X123108Y74755D01*
X122850Y74487D01*
X122747Y74218D01*
Y73873D01*
G01Y74218D02*
X122592Y74448D01*
X122333Y74640D01*
X122023Y74717D01*
X121713Y74640D01*
X121455Y74448D01*
X121300Y74103D01*
X121352Y73758D01*
X121558Y73413D01*
G01X124038Y76398D02*
X124297Y76667D01*
X124400Y76973D01*
X124297Y77280D01*
X123987Y77548D01*
X123522Y77740D01*
X123057Y77817D01*
X122488D01*
X122023Y77740D01*
X121610Y77548D01*
X121403Y77318D01*
X121300Y77050D01*
X121403Y76743D01*
X121610Y76513D01*
X121920Y76360D01*
X122333Y76283D01*
X122695Y76360D01*
X123057Y76552D01*
X123263Y76782D01*
X123315Y77050D01*
X123212Y77357D01*
X122953Y77587D01*
X122488Y77817D01*
G01X124038Y79498D02*
X124297Y79767D01*
X124400Y80073D01*
X124297Y80380D01*
X123987Y80648D01*
X123522Y80840D01*
X123057Y80917D01*
X122488D01*
X122023Y80840D01*
X121610Y80648D01*
X121403Y80418D01*
X121300Y80150D01*
X121403Y79843D01*
X121610Y79613D01*
X121920Y79460D01*
X122333Y79383D01*
X122695Y79460D01*
X123057Y79652D01*
X123263Y79882D01*
X123315Y80150D01*
X123212Y80457D01*
X122953Y80687D01*
X122488Y80917D01*
G01X118559Y75000D02*
X120331Y73500D01*
Y69760D01*
X111669D01*
Y80240D01*
X120331D01*
Y76500D01*
X118559Y75000D01*
G01X109184Y79951D02*
X102984D01*
Y83151D01*
X109184D01*
Y79951D01*
G01X111400Y85100D02*
X117600D01*
Y81900D01*
X111400D01*
Y85100D01*
G01X120400Y68100D02*
X126600D01*
Y64900D01*
X120400D01*
Y68100D01*
G01X117507Y94600D02*
Y92378D01*
X117660Y91913D01*
X117967Y91603D01*
X118350Y91500D01*
X118733Y91603D01*
X119040Y91913D01*
X119193Y92378D01*
Y94600D01*
G01X120607Y92120D02*
X120837Y91758D01*
X121143Y91552D01*
X121488Y91500D01*
X121795Y91552D01*
X122102Y91810D01*
X122293Y92120D01*
X122332Y92430D01*
X122255Y92792D01*
X121987Y93050D01*
X121718Y93153D01*
X121373D01*
G01X121718D02*
X121948Y93308D01*
X122140Y93567D01*
X122217Y93877D01*
X122140Y94187D01*
X121948Y94445D01*
X121603Y94600D01*
X121258Y94548D01*
X120913Y94342D01*
G01X124473Y91500D02*
X124550Y92172D01*
X124665Y92740D01*
X124818Y93257D01*
X125010Y93825D01*
X125317Y94600D01*
X123783D01*
G01X128110Y91500D02*
Y94600D01*
X126692Y92378D01*
X128608D01*
G01X108307Y106000D02*
Y109100D01*
X109073D01*
X109380Y108945D01*
X109610Y108738D01*
X109802Y108428D01*
X109955Y108067D01*
X109993Y107550D01*
X109955Y107033D01*
X109802Y106672D01*
X109610Y106362D01*
X109380Y106155D01*
X109073Y106000D01*
X108307D01*
G01X111522Y108583D02*
X111752Y108893D01*
X112020Y109048D01*
X112327Y109100D01*
X112710Y108997D01*
X112978Y108738D01*
X113055Y108428D01*
X113017Y108118D01*
X112863Y107860D01*
X112097Y107343D01*
X111752Y106982D01*
X111522Y106465D01*
X111445Y106000D01*
X113055D01*
G01X115350D02*
X115618Y106052D01*
X115925Y106207D01*
X116117Y106465D01*
X116193Y106827D01*
X116117Y107188D01*
X115887Y107498D01*
X115542Y107653D01*
X115158D01*
X114928Y107757D01*
X114737Y108015D01*
X114660Y108377D01*
X114775Y108738D01*
X115043Y108997D01*
X115350Y109100D01*
X115657Y108997D01*
X115925Y108738D01*
X116040Y108377D01*
X115963Y108015D01*
X115772Y107757D01*
X115542Y107653D01*
X115158D01*
X114813Y107498D01*
X114583Y107188D01*
X114507Y106827D01*
X114583Y106465D01*
X114775Y106207D01*
X115082Y106052D01*
X115350Y106000D01*
G01X117722Y107292D02*
X117990Y107653D01*
X118220Y107860D01*
X118527Y107963D01*
X118795Y107860D01*
X118987Y107653D01*
X119140Y107343D01*
X119178Y106982D01*
X119140Y106672D01*
X118987Y106362D01*
X118757Y106103D01*
X118488Y106000D01*
X118182Y106103D01*
X117913Y106413D01*
X117760Y106878D01*
X117722Y107395D01*
X117798Y108067D01*
X117913Y108428D01*
X118105Y108790D01*
X118373Y109048D01*
X118642Y109100D01*
X118910Y108997D01*
X119102Y108738D01*
G01X120200Y102900D02*
Y113100D01*
X124800D01*
Y102900D01*
X120200D01*
G01X113807Y124600D02*
Y122378D01*
X113960Y121913D01*
X114267Y121603D01*
X114650Y121500D01*
X115033Y121603D01*
X115340Y121913D01*
X115493Y122378D01*
Y124600D01*
G01X118210Y121500D02*
Y124600D01*
X116792Y122378D01*
X118708D01*
G01X120850Y124600D02*
X120543Y124497D01*
X120313Y124238D01*
X120160Y123928D01*
X120045Y123515D01*
X120007Y123050D01*
X120045Y122585D01*
X120160Y122172D01*
X120313Y121862D01*
X120543Y121603D01*
X120850Y121500D01*
X121157Y121603D01*
X121387Y121862D01*
X121540Y122172D01*
X121655Y122585D01*
X121693Y123050D01*
X121655Y123515D01*
X121540Y123928D01*
X121387Y124238D01*
X121157Y124497D01*
X120850Y124600D01*
G01X123950Y121500D02*
X124218Y121552D01*
X124525Y121707D01*
X124717Y121965D01*
X124793Y122327D01*
X124717Y122688D01*
X124487Y122998D01*
X124142Y123153D01*
X123758D01*
X123528Y123257D01*
X123337Y123515D01*
X123260Y123877D01*
X123375Y124238D01*
X123643Y124497D01*
X123950Y124600D01*
X124257Y124497D01*
X124525Y124238D01*
X124640Y123877D01*
X124563Y123515D01*
X124372Y123257D01*
X124142Y123153D01*
X123758D01*
X123413Y122998D01*
X123183Y122688D01*
X123107Y122327D01*
X123183Y121965D01*
X123375Y121707D01*
X123682Y121552D01*
X123950Y121500D01*
G01X106243Y135831D02*
Y127169D01*
X116757D01*
Y135831D01*
X106243D01*
G01X127427Y125410D02*
X125187D01*
G01X126400Y123785D02*
Y127035D01*
G01X104600Y134600D02*
Y128400D01*
X101400D01*
Y134600D01*
X104600D01*
G01X134000Y141500D02*
Y128500D01*
X119000D01*
Y141500D01*
X134000D01*
G01X112600Y118700D02*
X102400D01*
Y123300D01*
X112600D01*
Y118700D01*
G01X125100Y142900D02*
X118900D01*
Y146100D01*
X125100D01*
Y142900D01*
G01X118231Y353200D02*
Y337431D01*
X154569D01*
X159569Y342431D01*
Y353200D01*
G01X154569Y378769D02*
X118231D01*
Y363000D01*
G01X117559Y412000D02*
X119331Y410500D01*
Y406760D01*
X110669D01*
Y417240D01*
X119331D01*
Y413500D01*
X117559Y412000D01*
G01X123470Y404317D02*
X125692D01*
X126157Y404470D01*
X126467Y404777D01*
X126570Y405160D01*
X126467Y405543D01*
X126157Y405850D01*
X125692Y406003D01*
X123470D01*
G01X125950Y407417D02*
X126312Y407647D01*
X126518Y407953D01*
X126570Y408298D01*
X126518Y408605D01*
X126260Y408912D01*
X125950Y409103D01*
X125640Y409142D01*
X125278Y409065D01*
X125020Y408797D01*
X124917Y408528D01*
Y408183D01*
G01Y408528D02*
X124762Y408758D01*
X124503Y408950D01*
X124193Y409027D01*
X123883Y408950D01*
X123625Y408758D01*
X123470Y408413D01*
X123522Y408068D01*
X123728Y407723D01*
G01X126570Y411283D02*
X125898Y411360D01*
X125330Y411475D01*
X124813Y411628D01*
X124245Y411820D01*
X123470Y412127D01*
Y410593D01*
G01X123987Y413732D02*
X123677Y413962D01*
X123522Y414230D01*
X123470Y414537D01*
X123573Y414920D01*
X123832Y415188D01*
X124142Y415265D01*
X124452Y415227D01*
X124710Y415073D01*
X125227Y414307D01*
X125588Y413962D01*
X126105Y413732D01*
X126570Y413655D01*
Y415265D01*
G01X107900Y398900D02*
Y405100D01*
X111100D01*
Y398900D01*
X107900D01*
G01X115100Y405100D02*
Y398900D01*
X111900D01*
Y405100D01*
X115100D01*
G01X117900Y422807D02*
X120122D01*
X120587Y422960D01*
X120897Y423267D01*
X121000Y423650D01*
X120897Y424033D01*
X120587Y424340D01*
X120122Y424493D01*
X117900D01*
G01X121000Y427210D02*
X117900D01*
X120122Y425792D01*
Y427708D01*
G01X117900Y429850D02*
X118003Y429543D01*
X118262Y429313D01*
X118572Y429160D01*
X118985Y429045D01*
X119450Y429007D01*
X119915Y429045D01*
X120328Y429160D01*
X120638Y429313D01*
X120897Y429543D01*
X121000Y429850D01*
X120897Y430157D01*
X120638Y430387D01*
X120328Y430540D01*
X119915Y430655D01*
X119450Y430693D01*
X118985Y430655D01*
X118572Y430540D01*
X118262Y430387D01*
X118003Y430157D01*
X117900Y429850D01*
G01Y432950D02*
X118003Y432643D01*
X118262Y432413D01*
X118572Y432260D01*
X118985Y432145D01*
X119450Y432107D01*
X119915Y432145D01*
X120328Y432260D01*
X120638Y432413D01*
X120897Y432643D01*
X121000Y432950D01*
X120897Y433257D01*
X120638Y433487D01*
X120328Y433640D01*
X119915Y433755D01*
X119450Y433793D01*
X118985Y433755D01*
X118572Y433640D01*
X118262Y433487D01*
X118003Y433257D01*
X117900Y432950D01*
G01X116600Y425100D02*
Y418900D01*
X113400D01*
Y425100D01*
X116600D01*
G01X122900Y430600D02*
X129100D01*
Y427400D01*
X122900D01*
Y430600D01*
G01X125227Y451500D02*
X122987D01*
G01X124200Y449875D02*
Y453125D01*
G01X122900Y436600D02*
X129100D01*
Y433400D01*
X122900D01*
Y436600D01*
G01X126227Y468000D02*
X123987D01*
G01X125200Y466375D02*
Y469625D01*
G01X111900Y476900D02*
Y483100D01*
X115100D01*
Y476900D01*
X111900D01*
G01X117400D02*
Y483100D01*
X120600D01*
Y476900D01*
X117400D01*
G01X122900D02*
Y483100D01*
X126100D01*
Y476900D01*
X122900D01*
G01X107400D02*
Y483100D01*
X110600D01*
Y476900D01*
X107400D01*
G01X122900Y463300D02*
X133100D01*
Y458700D01*
X122900D01*
Y463300D01*
G01X112900Y499418D02*
X112650Y499578D01*
X112525Y499765D01*
X112483Y499978D01*
X112566Y500245D01*
X112775Y500432D01*
X113025Y500485D01*
X113275Y500458D01*
X113483Y500352D01*
X113900Y499818D01*
X114191Y499578D01*
X114608Y499418D01*
X114983Y499365D01*
Y500485D01*
G01Y502125D02*
X114941Y502312D01*
X114816Y502525D01*
X114608Y502658D01*
X114316Y502712D01*
X114025Y502658D01*
X113775Y502498D01*
X113650Y502258D01*
Y501992D01*
X113566Y501832D01*
X113358Y501698D01*
X113066Y501645D01*
X112775Y501725D01*
X112566Y501912D01*
X112483Y502125D01*
X112566Y502338D01*
X112775Y502525D01*
X113066Y502605D01*
X113358Y502552D01*
X113566Y502418D01*
X113650Y502258D01*
Y501992D01*
X113775Y501752D01*
X114025Y501592D01*
X114316Y501538D01*
X114608Y501592D01*
X114816Y501725D01*
X114941Y501938D01*
X114983Y502125D01*
G01X115929Y502895D02*
Y500429D01*
X118400D01*
G01X108100Y505100D02*
Y498900D01*
X104900D01*
Y505100D01*
X108100D01*
G01X115100Y492100D02*
Y485900D01*
X111900D01*
Y492100D01*
X115100D01*
G01X120600D02*
Y485900D01*
X117400D01*
Y492100D01*
X120600D01*
G01X122900Y485900D02*
Y492100D01*
X126100D01*
Y485900D01*
X122900D01*
G01X110600Y492100D02*
Y485900D01*
X107400D01*
Y492100D01*
X110600D01*
G01X112475Y514368D02*
X112225Y514528D01*
X112100Y514715D01*
X112058Y514928D01*
X112141Y515195D01*
X112350Y515382D01*
X112600Y515435D01*
X112850Y515408D01*
X113058Y515302D01*
X113475Y514768D01*
X113766Y514528D01*
X114183Y514368D01*
X114558Y514315D01*
Y515435D01*
G01X112475Y516568D02*
X112225Y516728D01*
X112100Y516915D01*
X112058Y517128D01*
X112141Y517395D01*
X112350Y517582D01*
X112600Y517635D01*
X112850Y517608D01*
X113058Y517502D01*
X113475Y516968D01*
X113766Y516728D01*
X114183Y516568D01*
X114558Y516515D01*
Y517635D01*
G01X118257Y517850D02*
X118097Y517600D01*
X117910Y517475D01*
X117697Y517433D01*
X117430Y517516D01*
X117243Y517725D01*
X117190Y517975D01*
X117217Y518225D01*
X117323Y518433D01*
X117857Y518850D01*
X118097Y519141D01*
X118257Y519558D01*
X118310Y519933D01*
X117190D01*
G01X115550D02*
Y517433D01*
X115870Y517933D01*
G01Y519933D02*
X115230D01*
G01X120800Y521500D02*
Y518500D01*
G01X112000Y508500D02*
X114000D01*
G01X118426Y516571D02*
X115929D01*
Y514085D01*
G01X117600Y528600D02*
Y522400D01*
X114400D01*
Y528600D01*
X117600D01*
G01X107600Y536100D02*
Y529900D01*
X104400D01*
Y536100D01*
X107600D01*
G01X111600D02*
Y529900D01*
X108400D01*
Y536100D01*
X111600D01*
G01X116100Y560600D02*
Y554400D01*
X112900D01*
Y560600D01*
X116100D01*
G01X126100Y559600D02*
Y553400D01*
X122900D01*
Y559600D01*
X126100D01*
G01X109100Y560600D02*
Y554400D01*
X105900D01*
Y560600D01*
X109100D01*
G01X126100Y569600D02*
Y563400D01*
X122900D01*
Y569600D01*
X126100D01*
G01X109100D02*
Y563400D01*
X105900D01*
Y569600D01*
X109100D01*
G01X118600D02*
Y563400D01*
X115400D01*
Y569600D01*
X118600D01*
G01X105400Y638400D02*
Y644600D01*
X108600D01*
Y638400D01*
X105400D01*
G01X119400D02*
Y644600D01*
X122600D01*
Y638400D01*
X119400D01*
G01X112400D02*
Y644600D01*
X115600D01*
Y638400D01*
X112400D01*
G01X103400Y626900D02*
Y633100D01*
X106600D01*
Y626900D01*
X103400D01*
G01X119400D02*
Y633100D01*
X122600D01*
Y626900D01*
X119400D01*
G01X112400D02*
Y633100D01*
X115600D01*
Y626900D01*
X112400D01*
G01X110900Y661100D02*
X117100D01*
Y657900D01*
X110900D01*
Y661100D01*
G01Y665100D02*
X117100D01*
Y661900D01*
X110900D01*
Y665100D01*
G01X117100Y665900D02*
X110900D01*
Y669100D01*
X117100D01*
Y665900D01*
G01Y669900D02*
X110900D01*
Y673100D01*
X117100D01*
Y669900D01*
G01Y673900D02*
X110900D01*
Y677100D01*
X117100D01*
Y673900D01*
G01Y677900D02*
X110900D01*
Y681100D01*
X117100D01*
Y677900D01*
G01Y681900D02*
X110900D01*
Y685100D01*
X117100D01*
Y681900D01*
G01Y685900D02*
X110900D01*
Y689100D01*
X117100D01*
Y685900D01*
G01X111100Y704900D02*
X104900D01*
Y708100D01*
X111100D01*
Y704900D01*
G01Y709400D02*
X104900D01*
Y712600D01*
X111100D01*
Y709400D01*
G01X116400Y705600D02*
X122600D01*
Y702400D01*
X116400D01*
Y705600D01*
G01Y712600D02*
X122600D01*
Y709400D01*
X116400D01*
Y712600D01*
G01X117100Y691400D02*
X110900D01*
Y694600D01*
X117100D01*
Y691400D01*
G01X120900Y696100D02*
X127100D01*
Y692900D01*
X120900D01*
Y696100D01*
G01X111100Y729400D02*
X104900D01*
Y732600D01*
X111100D01*
Y729400D01*
G01Y716400D02*
X104900D01*
Y719600D01*
X111100D01*
Y716400D01*
G01X116400Y719600D02*
X122600D01*
Y716400D01*
X116400D01*
Y719600D01*
G01Y732600D02*
X122600D01*
Y729400D01*
X116400D01*
Y732600D01*
G01X111100Y736400D02*
X104900D01*
Y739600D01*
X111100D01*
Y736400D01*
G01Y743400D02*
X104900D01*
Y746600D01*
X111100D01*
Y743400D01*
G01X116400Y739600D02*
X122600D01*
Y736400D01*
X116400D01*
Y739600D01*
G01Y746600D02*
X122600D01*
Y743400D01*
X116400D01*
Y746600D01*
G01X122600Y750400D02*
X116400D01*
Y753600D01*
X122600D01*
Y750400D01*
G01X117059Y777000D02*
X118831Y775500D01*
Y771760D01*
X110169D01*
Y782240D01*
X118831D01*
Y778500D01*
X117059Y777000D01*
G01X109900Y763900D02*
Y770100D01*
X113100D01*
Y763900D01*
X109900D01*
G01X119100Y770100D02*
Y763900D01*
X115900D01*
Y770100D01*
X119100D01*
G01X107900Y784807D02*
X110122D01*
X110587Y784960D01*
X110897Y785267D01*
X111000Y785650D01*
X110897Y786033D01*
X110587Y786340D01*
X110122Y786493D01*
X107900D01*
G01X111000Y789210D02*
X107900D01*
X110122Y787792D01*
Y789708D01*
G01X107900Y791850D02*
X108003Y791543D01*
X108262Y791313D01*
X108572Y791160D01*
X108985Y791045D01*
X109450Y791007D01*
X109915Y791045D01*
X110328Y791160D01*
X110638Y791313D01*
X110897Y791543D01*
X111000Y791850D01*
X110897Y792157D01*
X110638Y792387D01*
X110328Y792540D01*
X109915Y792655D01*
X109450Y792693D01*
X108985Y792655D01*
X108572Y792540D01*
X108262Y792387D01*
X108003Y792157D01*
X107900Y791850D01*
G01X111000Y794950D02*
X107900D01*
X108520Y794490D01*
G01X111000D02*
Y795410D01*
G01X120807Y790800D02*
Y788578D01*
X120960Y788113D01*
X121267Y787803D01*
X121650Y787700D01*
X122033Y787803D01*
X122340Y788113D01*
X122493Y788578D01*
Y790800D01*
G01X123907Y788320D02*
X124137Y787958D01*
X124443Y787752D01*
X124788Y787700D01*
X125095Y787752D01*
X125402Y788010D01*
X125593Y788320D01*
X125632Y788630D01*
X125555Y788992D01*
X125287Y789250D01*
X125018Y789353D01*
X124673D01*
G01X125018D02*
X125248Y789508D01*
X125440Y789767D01*
X125517Y790077D01*
X125440Y790387D01*
X125248Y790645D01*
X124903Y790800D01*
X124558Y790748D01*
X124213Y790542D01*
G01X127773Y787700D02*
X127850Y788372D01*
X127965Y788940D01*
X128118Y789457D01*
X128310Y790025D01*
X128617Y790800D01*
X127083D01*
G01X130950D02*
X130643Y790697D01*
X130413Y790438D01*
X130260Y790128D01*
X130145Y789715D01*
X130107Y789250D01*
X130145Y788785D01*
X130260Y788372D01*
X130413Y788062D01*
X130643Y787803D01*
X130950Y787700D01*
X131257Y787803D01*
X131487Y788062D01*
X131640Y788372D01*
X131755Y788785D01*
X131793Y789250D01*
X131755Y789715D01*
X131640Y790128D01*
X131487Y790438D01*
X131257Y790697D01*
X130950Y790800D01*
G01X116100Y790100D02*
Y783900D01*
X112900D01*
Y790100D01*
X116100D01*
G01X123727Y815000D02*
X121487D01*
G01X122700Y813375D02*
Y816625D01*
G01X124307Y808500D02*
Y811600D01*
X125073D01*
X125380Y811445D01*
X125610Y811238D01*
X125802Y810928D01*
X125955Y810567D01*
X125993Y810050D01*
X125955Y809533D01*
X125802Y809172D01*
X125610Y808862D01*
X125380Y808655D01*
X125073Y808500D01*
X124307D01*
G01X127522Y811083D02*
X127752Y811393D01*
X128020Y811548D01*
X128327Y811600D01*
X128710Y811497D01*
X128978Y811238D01*
X129055Y810928D01*
X129017Y810618D01*
X128863Y810360D01*
X128097Y809843D01*
X127752Y809482D01*
X127522Y808965D01*
X127445Y808500D01*
X129055D01*
G01X131273D02*
X131350Y809172D01*
X131465Y809740D01*
X131618Y810257D01*
X131810Y810825D01*
X132117Y811600D01*
X130583D01*
G01X134910Y808500D02*
Y811600D01*
X133492Y809378D01*
X135408D01*
G01X126227Y834386D02*
X123987D01*
G01X125200Y832761D02*
Y836011D01*
G01X123900Y831414D02*
X134100D01*
Y826814D01*
X123900D01*
Y831414D01*
G01X116831Y1080172D02*
Y1064403D01*
X153169D01*
X158169Y1069403D01*
Y1080172D01*
G01X153169Y1105741D02*
X116831D01*
Y1089972D01*
G01X109400Y1147307D02*
X111622D01*
X112087Y1147460D01*
X112397Y1147767D01*
X112500Y1148150D01*
X112397Y1148533D01*
X112087Y1148840D01*
X111622Y1148993D01*
X109400D01*
G01X112500Y1151710D02*
X109400D01*
X111622Y1150292D01*
Y1152208D01*
G01X109400Y1154350D02*
X109503Y1154043D01*
X109762Y1153813D01*
X110072Y1153660D01*
X110485Y1153545D01*
X110950Y1153507D01*
X111415Y1153545D01*
X111828Y1153660D01*
X112138Y1153813D01*
X112397Y1154043D01*
X112500Y1154350D01*
X112397Y1154657D01*
X112138Y1154887D01*
X111828Y1155040D01*
X111415Y1155155D01*
X110950Y1155193D01*
X110485Y1155155D01*
X110072Y1155040D01*
X109762Y1154887D01*
X109503Y1154657D01*
X109400Y1154350D01*
G01X109917Y1156722D02*
X109607Y1156952D01*
X109452Y1157220D01*
X109400Y1157527D01*
X109503Y1157910D01*
X109762Y1158178D01*
X110072Y1158255D01*
X110382Y1158217D01*
X110640Y1158063D01*
X111157Y1157297D01*
X111518Y1156952D01*
X112035Y1156722D01*
X112500Y1156645D01*
Y1158255D01*
G01X118059Y1140000D02*
X119831Y1138500D01*
Y1134760D01*
X111169D01*
Y1145240D01*
X119831D01*
Y1141500D01*
X118059Y1140000D01*
G01X117100Y1153100D02*
Y1146900D01*
X113900D01*
Y1153100D01*
X117100D01*
G01X110900Y1126900D02*
Y1133100D01*
X114100D01*
Y1126900D01*
X110900D01*
G01X120100Y1133100D02*
Y1126900D01*
X116900D01*
Y1133100D01*
X120100D01*
G01X121807Y1154600D02*
Y1152378D01*
X121960Y1151913D01*
X122267Y1151603D01*
X122650Y1151500D01*
X123033Y1151603D01*
X123340Y1151913D01*
X123493Y1152378D01*
Y1154600D01*
G01X124907Y1152120D02*
X125137Y1151758D01*
X125443Y1151552D01*
X125788Y1151500D01*
X126095Y1151552D01*
X126402Y1151810D01*
X126593Y1152120D01*
X126632Y1152430D01*
X126555Y1152792D01*
X126287Y1153050D01*
X126018Y1153153D01*
X125673D01*
G01X126018D02*
X126248Y1153308D01*
X126440Y1153567D01*
X126517Y1153877D01*
X126440Y1154187D01*
X126248Y1154445D01*
X125903Y1154600D01*
X125558Y1154548D01*
X125213Y1154342D01*
G01X128122Y1152792D02*
X128390Y1153153D01*
X128620Y1153360D01*
X128927Y1153463D01*
X129195Y1153360D01*
X129387Y1153153D01*
X129540Y1152843D01*
X129578Y1152482D01*
X129540Y1152172D01*
X129387Y1151862D01*
X129157Y1151603D01*
X128888Y1151500D01*
X128582Y1151603D01*
X128313Y1151913D01*
X128160Y1152378D01*
X128122Y1152895D01*
X128198Y1153567D01*
X128313Y1153928D01*
X128505Y1154290D01*
X128773Y1154548D01*
X129042Y1154600D01*
X129310Y1154497D01*
X129502Y1154238D01*
G01X131950Y1151500D02*
X132218Y1151552D01*
X132525Y1151707D01*
X132717Y1151965D01*
X132793Y1152327D01*
X132717Y1152688D01*
X132487Y1152998D01*
X132142Y1153153D01*
X131758D01*
X131528Y1153257D01*
X131337Y1153515D01*
X131260Y1153877D01*
X131375Y1154238D01*
X131643Y1154497D01*
X131950Y1154600D01*
X132257Y1154497D01*
X132525Y1154238D01*
X132640Y1153877D01*
X132563Y1153515D01*
X132372Y1153257D01*
X132142Y1153153D01*
X131758D01*
X131413Y1152998D01*
X131183Y1152688D01*
X131107Y1152327D01*
X131183Y1151965D01*
X131375Y1151707D01*
X131682Y1151552D01*
X131950Y1151500D01*
G01X113807Y1169600D02*
Y1167378D01*
X113960Y1166913D01*
X114267Y1166603D01*
X114650Y1166500D01*
X115033Y1166603D01*
X115340Y1166913D01*
X115493Y1167378D01*
Y1169600D01*
G01X116907Y1167120D02*
X117137Y1166758D01*
X117443Y1166552D01*
X117788Y1166500D01*
X118095Y1166552D01*
X118402Y1166810D01*
X118593Y1167120D01*
X118632Y1167430D01*
X118555Y1167792D01*
X118287Y1168050D01*
X118018Y1168153D01*
X117673D01*
G01X118018D02*
X118248Y1168308D01*
X118440Y1168567D01*
X118517Y1168877D01*
X118440Y1169187D01*
X118248Y1169445D01*
X117903Y1169600D01*
X117558Y1169548D01*
X117213Y1169342D01*
G01X120122Y1167792D02*
X120390Y1168153D01*
X120620Y1168360D01*
X120927Y1168463D01*
X121195Y1168360D01*
X121387Y1168153D01*
X121540Y1167843D01*
X121578Y1167482D01*
X121540Y1167172D01*
X121387Y1166862D01*
X121157Y1166603D01*
X120888Y1166500D01*
X120582Y1166603D01*
X120313Y1166913D01*
X120160Y1167378D01*
X120122Y1167895D01*
X120198Y1168567D01*
X120313Y1168928D01*
X120505Y1169290D01*
X120773Y1169548D01*
X121042Y1169600D01*
X121310Y1169497D01*
X121502Y1169238D01*
G01X123298Y1166862D02*
X123567Y1166603D01*
X123873Y1166500D01*
X124180Y1166603D01*
X124448Y1166913D01*
X124640Y1167378D01*
X124717Y1167843D01*
Y1168412D01*
X124640Y1168877D01*
X124448Y1169290D01*
X124218Y1169497D01*
X123950Y1169600D01*
X123643Y1169497D01*
X123413Y1169290D01*
X123260Y1168980D01*
X123183Y1168567D01*
X123260Y1168205D01*
X123452Y1167843D01*
X123682Y1167637D01*
X123950Y1167585D01*
X124257Y1167688D01*
X124487Y1167947D01*
X124717Y1168412D01*
G01X123727Y1177500D02*
X121487D01*
G01X122700Y1175875D02*
Y1179125D01*
G01X124545Y1197934D02*
X122305D01*
G01X123518Y1196309D02*
Y1199559D01*
G01X122900Y1194800D02*
X133100D01*
Y1190200D01*
X122900D01*
Y1194800D01*
G01X136200Y60727D02*
Y58487D01*
G01X137825Y59700D02*
X134575D01*
G01X143681Y65969D02*
Y62031D01*
G01X141319Y65969D02*
Y62031D01*
X143287Y64000D01*
X141319Y65969D01*
G01X136000Y66800D02*
X150500D01*
Y61200D01*
X136000D01*
Y66800D01*
G01X150000Y40807D02*
X146900D01*
Y41573D01*
X147055Y41880D01*
X147262Y42110D01*
X147572Y42302D01*
X147933Y42455D01*
X148450Y42493D01*
X148967Y42455D01*
X149328Y42302D01*
X149638Y42110D01*
X149845Y41880D01*
X150000Y41573D01*
Y40807D01*
G01X147417Y44022D02*
X147107Y44252D01*
X146952Y44520D01*
X146900Y44827D01*
X147003Y45210D01*
X147262Y45478D01*
X147572Y45555D01*
X147882Y45517D01*
X148140Y45363D01*
X148657Y44597D01*
X149018Y44252D01*
X149535Y44022D01*
X150000Y43945D01*
Y45555D01*
G01Y47850D02*
X149948Y48118D01*
X149793Y48425D01*
X149535Y48617D01*
X149173Y48693D01*
X148812Y48617D01*
X148502Y48387D01*
X148347Y48042D01*
Y47658D01*
X148243Y47428D01*
X147985Y47237D01*
X147623Y47160D01*
X147262Y47275D01*
X147003Y47543D01*
X146900Y47850D01*
X147003Y48157D01*
X147262Y48425D01*
X147623Y48540D01*
X147985Y48463D01*
X148243Y48272D01*
X148347Y48042D01*
Y47658D01*
X148502Y47313D01*
X148812Y47083D01*
X149173Y47007D01*
X149535Y47083D01*
X149793Y47275D01*
X149948Y47582D01*
X150000Y47850D01*
G01X149380Y50107D02*
X149742Y50337D01*
X149948Y50643D01*
X150000Y50988D01*
X149948Y51295D01*
X149690Y51602D01*
X149380Y51793D01*
X149070Y51832D01*
X148708Y51755D01*
X148450Y51487D01*
X148347Y51218D01*
Y50873D01*
G01Y51218D02*
X148192Y51448D01*
X147933Y51640D01*
X147623Y51717D01*
X147313Y51640D01*
X147055Y51448D01*
X146900Y51103D01*
X146952Y50758D01*
X147158Y50413D01*
G01X147400Y59927D02*
X150100Y59827D01*
X147000D01*
G01X150272Y60220D02*
X146728D01*
Y53134D01*
X150272D01*
Y60142D01*
G01X145100Y59600D02*
Y53400D01*
X141900D01*
Y59600D01*
X145100D01*
G01X124400Y61800D02*
X134600D01*
Y57200D01*
X124400D01*
Y61800D01*
G01X130243Y77331D02*
Y68669D01*
X140757D01*
Y77331D01*
X130243D01*
G01Y93331D02*
Y84669D01*
X140757D01*
Y93331D01*
X130243D01*
G01X142727Y78500D02*
X140487D01*
G01X141700Y76875D02*
Y80125D01*
G01X150720Y78070D02*
Y81614D01*
X143634D01*
Y78070D01*
X150642D01*
G01X125400Y69900D02*
Y76100D01*
X128600D01*
Y69900D01*
X125400D01*
G01Y83900D02*
Y90100D01*
X128600D01*
Y83900D01*
X125400D01*
G01X134600Y63400D02*
X128400D01*
Y66600D01*
X134600D01*
Y63400D01*
G01X146100Y76100D02*
Y69900D01*
X142900D01*
Y76100D01*
X146100D01*
G01Y90100D02*
Y83900D01*
X142900D01*
Y90100D01*
X146100D01*
G01X133900Y82600D02*
X140100D01*
Y79400D01*
X133900D01*
Y82600D01*
G01X138727Y112500D02*
X136487D01*
G01X137700Y110875D02*
Y114125D01*
G01X149913Y112500D02*
X147487D01*
G01X142727Y94500D02*
X140487D01*
G01X141700Y92875D02*
Y96125D01*
G01X150720Y92228D02*
Y95772D01*
X143634D01*
Y92228D01*
X150642D01*
G01X128127Y103300D02*
X125887D01*
G01X127100Y101675D02*
Y104925D01*
G01X134413Y104500D02*
X131987D01*
G01X133220Y105956D02*
Y109500D01*
X126134D01*
Y105956D01*
X133142D01*
G01X132927Y108828D02*
X132827Y106128D01*
Y109228D01*
G01X150100Y106242D02*
X143900D01*
Y109442D01*
X150100D01*
Y106242D01*
G01X143900Y104942D02*
X150100D01*
Y101742D01*
X143900D01*
Y104942D01*
G01X150100Y97242D02*
X143900D01*
Y100442D01*
X150100D01*
Y97242D01*
G01X141600Y106242D02*
X135400D01*
Y109442D01*
X141600D01*
Y106242D01*
G01X133900Y98600D02*
X140100D01*
Y95400D01*
X133900D01*
Y98600D01*
G01X133273Y117000D02*
X135513D01*
G01X134300Y118625D02*
Y115375D01*
G01X144181Y121311D02*
Y117373D01*
G01X141819Y121311D02*
Y117373D01*
X143787Y119342D01*
X141819Y121311D01*
G01X136500Y122142D02*
X151000D01*
Y116542D01*
X136500D01*
Y122142D01*
G01X146720Y111070D02*
Y114614D01*
X139634D01*
Y111070D01*
X146642D01*
G01X146427Y113942D02*
X146327Y111242D01*
Y114342D01*
G01X139533Y123810D02*
X137107D01*
G01X137807Y129500D02*
Y132600D01*
X138573D01*
X138880Y132445D01*
X139110Y132238D01*
X139302Y131928D01*
X139455Y131567D01*
X139493Y131050D01*
X139455Y130533D01*
X139302Y130172D01*
X139110Y129862D01*
X138880Y129655D01*
X138573Y129500D01*
X137807D01*
G01X141022Y132083D02*
X141252Y132393D01*
X141520Y132548D01*
X141827Y132600D01*
X142210Y132497D01*
X142478Y132238D01*
X142555Y131928D01*
X142517Y131618D01*
X142363Y131360D01*
X141597Y130843D01*
X141252Y130482D01*
X141022Y129965D01*
X140945Y129500D01*
X142555D01*
G01X144850D02*
X145118Y129552D01*
X145425Y129707D01*
X145617Y129965D01*
X145693Y130327D01*
X145617Y130688D01*
X145387Y130998D01*
X145042Y131153D01*
X144658D01*
X144428Y131257D01*
X144237Y131515D01*
X144160Y131877D01*
X144275Y132238D01*
X144543Y132497D01*
X144850Y132600D01*
X145157Y132497D01*
X145425Y132238D01*
X145540Y131877D01*
X145463Y131515D01*
X145272Y131257D01*
X145042Y131153D01*
X144658D01*
X144313Y130998D01*
X144083Y130688D01*
X144007Y130327D01*
X144083Y129965D01*
X144275Y129707D01*
X144582Y129552D01*
X144850Y129500D01*
G01X147107Y129965D02*
X147337Y129707D01*
X147605Y129552D01*
X147950Y129500D01*
X148295Y129603D01*
X148563Y129810D01*
X148755Y130172D01*
X148793Y130585D01*
X148717Y130998D01*
X148525Y131257D01*
X148257Y131463D01*
X147988Y131515D01*
X147720Y131463D01*
X147375Y131257D01*
X147490Y132600D01*
X148525D01*
G01X135720Y122728D02*
Y126272D01*
X128634D01*
Y122728D01*
X135642D01*
G01X135427Y125600D02*
X135327Y122900D01*
Y126000D01*
G01X144400Y128442D02*
X150600D01*
Y125242D01*
X144400D01*
Y128442D01*
G01X143100Y125242D02*
X136900D01*
Y128442D01*
X143100D01*
Y125242D01*
G01X132600Y116400D02*
X126400D01*
Y119600D01*
X132600D01*
Y116400D01*
G01Y112400D02*
X126400D01*
Y115600D01*
X132600D01*
Y112400D01*
G01X142485Y150231D02*
Y139462D01*
X147485Y134462D01*
G01X129220Y143900D02*
X128913Y143952D01*
X128645Y144158D01*
X128415Y144468D01*
X128262Y144830D01*
X128185Y145243D01*
Y145657D01*
X128262Y146070D01*
X128415Y146432D01*
X128645Y146742D01*
X128913Y146948D01*
X129220Y147000D01*
X129527Y146948D01*
X129795Y146742D01*
X130025Y146432D01*
X130178Y146070D01*
X130255Y145657D01*
Y145243D01*
X130178Y144830D01*
X130025Y144468D01*
X129795Y144158D01*
X129527Y143952D01*
X129220Y143900D01*
G01X129527Y144727D02*
X129987Y143900D01*
G01X132320D02*
Y147000D01*
X131860Y146380D01*
G01Y143900D02*
X132780D01*
G01X134692Y146483D02*
X134922Y146793D01*
X135190Y146948D01*
X135497Y147000D01*
X135880Y146897D01*
X136148Y146638D01*
X136225Y146328D01*
X136187Y146018D01*
X136033Y145760D01*
X135267Y145243D01*
X134922Y144882D01*
X134692Y144365D01*
X134615Y143900D01*
X136225D01*
G01X183823Y160031D02*
Y175800D01*
X147485D01*
X142485Y170800D01*
Y160031D01*
G01X141400Y250600D02*
X147600D01*
Y247400D01*
X141400D01*
Y250600D01*
G01X147600Y251400D02*
X141400D01*
Y254600D01*
X147600D01*
Y251400D01*
G01X147582Y261128D02*
X141382D01*
Y264328D01*
X147582D01*
Y261128D01*
G01X141400Y258600D02*
X147600D01*
Y255400D01*
X141400D01*
Y258600D01*
G01X134882Y262628D02*
Y268828D01*
X138082D01*
Y262628D01*
X134882D01*
G01X140600Y258600D02*
Y252400D01*
X137400D01*
Y258600D01*
X140600D01*
G01X146900Y385900D02*
Y392100D01*
X150100D01*
Y385900D01*
X146900D01*
G01X136273Y402000D02*
X138513D01*
G01X137300Y403625D02*
Y400375D01*
G01X148087Y402500D02*
X150513D01*
G01X136500Y410028D02*
X151000D01*
Y404428D01*
X136500D01*
Y410028D01*
G01X141819Y409197D02*
Y405259D01*
X143787Y407228D01*
X141819Y409197D01*
G01X144181D02*
Y405259D01*
G01X138227Y397500D02*
X135987D01*
G01X137200Y395875D02*
Y399125D01*
G01X150413Y400000D02*
X147987D01*
G01X139807Y393300D02*
Y396400D01*
X140573D01*
X140880Y396245D01*
X141110Y396038D01*
X141302Y395728D01*
X141455Y395367D01*
X141493Y394850D01*
X141455Y394333D01*
X141302Y393972D01*
X141110Y393662D01*
X140880Y393455D01*
X140573Y393300D01*
X139807D01*
G01X143022Y395883D02*
X143252Y396193D01*
X143520Y396348D01*
X143827Y396400D01*
X144210Y396297D01*
X144478Y396038D01*
X144555Y395728D01*
X144517Y395418D01*
X144363Y395160D01*
X143597Y394643D01*
X143252Y394282D01*
X143022Y393765D01*
X142945Y393300D01*
X144555D01*
G01X146773D02*
X146850Y393972D01*
X146965Y394540D01*
X147118Y395057D01*
X147310Y395625D01*
X147617Y396400D01*
X146083D01*
G01X149873Y393300D02*
X149950Y393972D01*
X150065Y394540D01*
X150218Y395057D01*
X150410Y395625D01*
X150717Y396400D01*
X149183D01*
G01X146427Y401828D02*
X146327Y399128D01*
Y402228D01*
G01X146720Y398956D02*
Y402500D01*
X139634D01*
Y398956D01*
X146642D01*
G01X134100Y406400D02*
X127900D01*
Y409600D01*
X134100D01*
Y406400D01*
G01Y402128D02*
X127900D01*
Y405328D01*
X134100D01*
Y402128D01*
G01X124675Y401800D02*
X134875D01*
Y397200D01*
X124675D01*
Y401800D01*
G01X130743Y420831D02*
Y412169D01*
X141257D01*
Y420831D01*
X130743D01*
G01Y436831D02*
Y428169D01*
X141257D01*
Y436831D01*
X130743D01*
G01X143007Y426870D02*
X140767D01*
G01X141980Y425245D02*
Y428495D01*
G01X150720Y426228D02*
Y429772D01*
X143634D01*
Y426228D01*
X150642D01*
G01X143727Y416210D02*
X141487D01*
G01X142700Y414585D02*
Y417835D01*
G01X150413Y417000D02*
X147987D01*
G01X150720Y411956D02*
Y415500D01*
X143634D01*
Y411956D01*
X150642D01*
G01X125900Y416900D02*
Y423100D01*
X129100D01*
Y416900D01*
X125900D01*
G01X143400Y431400D02*
Y437600D01*
X146600D01*
Y431400D01*
X143400D01*
G01X142900Y418400D02*
Y424600D01*
X146100D01*
Y418400D01*
X142900D01*
G01X134900Y426100D02*
X141100D01*
Y422900D01*
X134900D01*
Y426100D01*
G01X134273Y459000D02*
X136513D01*
G01X135300Y460625D02*
Y457375D01*
G01X130607Y441367D02*
Y439145D01*
X130760Y438680D01*
X131067Y438370D01*
X131450Y438267D01*
X131833Y438370D01*
X132140Y438680D01*
X132293Y439145D01*
Y441367D01*
G01X133707Y438887D02*
X133937Y438525D01*
X134243Y438319D01*
X134588Y438267D01*
X134895Y438319D01*
X135202Y438577D01*
X135393Y438887D01*
X135432Y439197D01*
X135355Y439559D01*
X135087Y439817D01*
X134818Y439920D01*
X134473D01*
G01X134818D02*
X135048Y440075D01*
X135240Y440334D01*
X135317Y440644D01*
X135240Y440954D01*
X135048Y441212D01*
X134703Y441367D01*
X134358Y441315D01*
X134013Y441109D01*
G01X137573Y438267D02*
X137650Y438939D01*
X137765Y439507D01*
X137918Y440024D01*
X138110Y440592D01*
X138417Y441367D01*
X136883D01*
G01X139907Y438887D02*
X140137Y438525D01*
X140443Y438319D01*
X140788Y438267D01*
X141095Y438319D01*
X141402Y438577D01*
X141593Y438887D01*
X141632Y439197D01*
X141555Y439559D01*
X141287Y439817D01*
X141018Y439920D01*
X140673D01*
G01X141018D02*
X141248Y440075D01*
X141440Y440334D01*
X141517Y440644D01*
X141440Y440954D01*
X141248Y441212D01*
X140903Y441367D01*
X140558Y441315D01*
X140213Y441109D01*
G01X138727Y456000D02*
X136487D01*
G01X137700Y454375D02*
Y457625D01*
G01X149913Y456000D02*
X147487D01*
G01X146427Y457828D02*
X146327Y455128D01*
Y458228D01*
G01X146720Y454956D02*
Y458500D01*
X139634D01*
Y454956D01*
X146642D01*
G01X132913Y448500D02*
X130487D01*
G01X130807Y444500D02*
Y447600D01*
X131573D01*
X131880Y447445D01*
X132110Y447238D01*
X132302Y446928D01*
X132455Y446567D01*
X132493Y446050D01*
X132455Y445533D01*
X132302Y445172D01*
X132110Y444862D01*
X131880Y444655D01*
X131573Y444500D01*
X130807D01*
G01X134022Y447083D02*
X134252Y447393D01*
X134520Y447548D01*
X134827Y447600D01*
X135210Y447497D01*
X135478Y447238D01*
X135555Y446928D01*
X135517Y446618D01*
X135363Y446360D01*
X134597Y445843D01*
X134252Y445482D01*
X134022Y444965D01*
X133945Y444500D01*
X135555D01*
G01X137850D02*
X138118Y444552D01*
X138425Y444707D01*
X138617Y444965D01*
X138693Y445327D01*
X138617Y445688D01*
X138387Y445998D01*
X138042Y446153D01*
X137658D01*
X137428Y446257D01*
X137237Y446515D01*
X137160Y446877D01*
X137275Y447238D01*
X137543Y447497D01*
X137850Y447600D01*
X138157Y447497D01*
X138425Y447238D01*
X138540Y446877D01*
X138463Y446515D01*
X138272Y446257D01*
X138042Y446153D01*
X137658D01*
X137313Y445998D01*
X137083Y445688D01*
X137007Y445327D01*
X137083Y444965D01*
X137275Y444707D01*
X137582Y444552D01*
X137850Y444500D01*
G01X140950Y447600D02*
X140643Y447497D01*
X140413Y447238D01*
X140260Y446928D01*
X140145Y446515D01*
X140107Y446050D01*
X140145Y445585D01*
X140260Y445172D01*
X140413Y444862D01*
X140643Y444603D01*
X140950Y444500D01*
X141257Y444603D01*
X141487Y444862D01*
X141640Y445172D01*
X141755Y445585D01*
X141793Y446050D01*
X141755Y446515D01*
X141640Y446928D01*
X141487Y447238D01*
X141257Y447497D01*
X140950Y447600D01*
G01X132927Y452714D02*
X132827Y450014D01*
Y453114D01*
G01X133220Y449842D02*
Y453386D01*
X126134D01*
Y449842D01*
X133142D01*
G01X150100Y441128D02*
X143900D01*
Y444328D01*
X150100D01*
Y441128D01*
G01X143900Y448828D02*
X150100D01*
Y445628D01*
X143900D01*
Y448828D01*
G01X150100Y450128D02*
X143900D01*
Y453328D01*
X150100D01*
Y450128D01*
G01X133100Y455128D02*
X126900D01*
Y458328D01*
X133100D01*
Y455128D01*
G01X141600Y450128D02*
X135400D01*
Y453328D01*
X141600D01*
Y450128D01*
G01X136500Y465800D02*
Y460200D01*
X150500D01*
Y465800D01*
X136500D01*
G01X146587Y467000D02*
X149013D01*
G01X141819Y464969D02*
Y461031D01*
X143787Y463000D01*
X141819Y464969D01*
G01X144181D02*
Y461031D01*
G01X135913Y468000D02*
X133487D01*
G01X138307Y473500D02*
Y476600D01*
X139073D01*
X139380Y476445D01*
X139610Y476238D01*
X139802Y475928D01*
X139955Y475567D01*
X139993Y475050D01*
X139955Y474533D01*
X139802Y474172D01*
X139610Y473862D01*
X139380Y473655D01*
X139073Y473500D01*
X138307D01*
G01X141522Y476083D02*
X141752Y476393D01*
X142020Y476548D01*
X142327Y476600D01*
X142710Y476497D01*
X142978Y476238D01*
X143055Y475928D01*
X143017Y475618D01*
X142863Y475360D01*
X142097Y474843D01*
X141752Y474482D01*
X141522Y473965D01*
X141445Y473500D01*
X143055D01*
G01X145273D02*
X145350Y474172D01*
X145465Y474740D01*
X145618Y475257D01*
X145810Y475825D01*
X146117Y476600D01*
X144583D01*
G01X147798Y473862D02*
X148067Y473603D01*
X148373Y473500D01*
X148680Y473603D01*
X148948Y473913D01*
X149140Y474378D01*
X149217Y474843D01*
Y475412D01*
X149140Y475877D01*
X148948Y476290D01*
X148718Y476497D01*
X148450Y476600D01*
X148143Y476497D01*
X147913Y476290D01*
X147760Y475980D01*
X147683Y475567D01*
X147760Y475205D01*
X147952Y474843D01*
X148182Y474637D01*
X148450Y474585D01*
X148757Y474688D01*
X148987Y474947D01*
X149217Y475412D01*
G01X133427Y471828D02*
X133327Y469128D01*
Y472228D01*
G01X133720Y468956D02*
Y472500D01*
X126634D01*
Y468956D01*
X133642D01*
G01X144400Y472328D02*
X150600D01*
Y469128D01*
X144400D01*
Y472328D01*
G01X133900Y476900D02*
Y483100D01*
X137100D01*
Y476900D01*
X133900D01*
G01X128400D02*
Y483100D01*
X131600D01*
Y476900D01*
X128400D01*
G01X142100Y469128D02*
X135900D01*
Y472328D01*
X142100D01*
Y469128D01*
G01X133100Y463900D02*
X126900D01*
Y467100D01*
X133100D01*
Y463900D01*
G01X139400Y500807D02*
X141622D01*
X142087Y500960D01*
X142397Y501267D01*
X142500Y501650D01*
X142397Y502033D01*
X142087Y502340D01*
X141622Y502493D01*
X139400D01*
G01X141880Y503907D02*
X142242Y504137D01*
X142448Y504443D01*
X142500Y504788D01*
X142448Y505095D01*
X142190Y505402D01*
X141880Y505593D01*
X141570Y505632D01*
X141208Y505555D01*
X140950Y505287D01*
X140847Y505018D01*
Y504673D01*
G01Y505018D02*
X140692Y505248D01*
X140433Y505440D01*
X140123Y505517D01*
X139813Y505440D01*
X139555Y505248D01*
X139400Y504903D01*
X139452Y504558D01*
X139658Y504213D01*
G01X142500Y507850D02*
X139400D01*
X140020Y507390D01*
G01X142500D02*
Y508310D01*
G01Y510873D02*
X141828Y510950D01*
X141260Y511065D01*
X140743Y511218D01*
X140175Y511410D01*
X139400Y511717D01*
Y510183D01*
G01X135308Y501725D02*
X135266Y501912D01*
X135141Y502125D01*
X134933Y502258D01*
X134641Y502312D01*
X134350Y502258D01*
X134100Y502098D01*
X133975Y501858D01*
Y501592D01*
X133891Y501432D01*
X133683Y501298D01*
X133391Y501245D01*
X133100Y501325D01*
X132891Y501512D01*
X132808Y501725D01*
X132891Y501938D01*
X133100Y502125D01*
X133391Y502205D01*
X133683Y502152D01*
X133891Y502018D01*
X133975Y501858D01*
Y501592D01*
X134100Y501352D01*
X134350Y501192D01*
X134641Y501138D01*
X134933Y501192D01*
X135141Y501325D01*
X135266Y501538D01*
X135308Y501725D01*
G01X132253Y499000D02*
X132200Y498458D01*
X132120Y498000D01*
X132013Y497583D01*
X131880Y497125D01*
X131667Y496500D01*
X132733D01*
G01X125568Y498480D02*
Y496480D01*
G01X129590Y500429D02*
X132071D01*
Y502918D01*
G01X137100Y492100D02*
Y485900D01*
X133900D01*
Y492100D01*
X137100D01*
G01X128400Y485900D02*
Y492100D01*
X131600D01*
Y485900D01*
X128400D01*
G01X152025Y485400D02*
X145825D01*
Y488600D01*
X152025D01*
Y485400D01*
G01X152100Y490400D02*
X145900D01*
Y493600D01*
X152100D01*
Y490400D01*
G01Y495400D02*
X145900D01*
Y498600D01*
X152100D01*
Y495400D01*
G01Y500400D02*
X145900D01*
Y503600D01*
X152100D01*
Y500400D01*
G01X132375Y519983D02*
Y517483D01*
X132695Y517983D01*
G01Y519983D02*
X132055D01*
G01X130762Y519608D02*
X130602Y519816D01*
X130415Y519941D01*
X130175Y519983D01*
X129935Y519900D01*
X129748Y519733D01*
X129615Y519441D01*
X129588Y519108D01*
X129642Y518775D01*
X129775Y518566D01*
X129962Y518400D01*
X130148Y518358D01*
X130335Y518400D01*
X130575Y518566D01*
X130495Y517483D01*
X129775D01*
G01X135933Y514500D02*
X133433D01*
X133933Y514180D01*
G01X135933D02*
Y514820D01*
G01Y517020D02*
X133433D01*
X135225Y516033D01*
Y517367D01*
G01X128800Y520500D02*
Y518500D01*
G01X134000Y506900D02*
X137000D01*
G01X132071Y514105D02*
Y516571D01*
G01D02*
X129580D01*
G01X152100Y505400D02*
X145900D01*
Y508600D01*
X152100D01*
Y505400D01*
G01Y510400D02*
X145900D01*
Y513600D01*
X152100D01*
Y510400D01*
G01Y515400D02*
X145900D01*
Y518600D01*
X152100D01*
Y515400D01*
G01Y520400D02*
X145900D01*
Y523600D01*
X152100D01*
Y520400D01*
G01Y525400D02*
X145900D01*
Y528600D01*
X152100D01*
Y525400D01*
G01Y530400D02*
X145900D01*
Y533600D01*
X152100D01*
Y530400D01*
G01Y535400D02*
X145900D01*
Y538600D01*
X152100D01*
Y535400D01*
G01X152025Y540400D02*
X145825D01*
Y543600D01*
X152025D01*
Y540400D01*
G01X133100Y559600D02*
Y553400D01*
X129900D01*
Y559600D01*
X133100D01*
G01X137100D02*
Y553400D01*
X133900D01*
Y559600D01*
X137100D01*
G01Y569600D02*
Y563400D01*
X133900D01*
Y569600D01*
X137100D01*
G01X133100D02*
Y563400D01*
X129900D01*
Y569600D01*
X133100D01*
G01X133400Y626900D02*
Y633100D01*
X136600D01*
Y626900D01*
X133400D01*
G01X129400D02*
Y633100D01*
X132600D01*
Y626900D01*
X129400D01*
G01X136900Y638400D02*
Y644600D01*
X140100D01*
Y638400D01*
X136900D01*
G01X124900D02*
Y644600D01*
X128100D01*
Y638400D01*
X124900D01*
G01X146807Y658600D02*
Y656378D01*
X146960Y655913D01*
X147267Y655603D01*
X147650Y655500D01*
X148033Y655603D01*
X148340Y655913D01*
X148493Y656378D01*
Y658600D01*
G01X150750Y655500D02*
X151018Y655552D01*
X151325Y655707D01*
X151517Y655965D01*
X151593Y656327D01*
X151517Y656688D01*
X151287Y656998D01*
X150942Y657153D01*
X150558D01*
X150328Y657257D01*
X150137Y657515D01*
X150060Y657877D01*
X150175Y658238D01*
X150443Y658497D01*
X150750Y658600D01*
X151057Y658497D01*
X151325Y658238D01*
X151440Y657877D01*
X151363Y657515D01*
X151172Y657257D01*
X150942Y657153D01*
X150558D01*
X150213Y656998D01*
X149983Y656688D01*
X149907Y656327D01*
X149983Y655965D01*
X150175Y655707D01*
X150482Y655552D01*
X150750Y655500D01*
G01X135100Y659900D02*
Y691100D01*
X150900D01*
Y659900D01*
X145300D01*
X143000Y662200D01*
X140700Y659900D01*
X135100D01*
G01X129900Y658100D02*
X136100D01*
Y654900D01*
X129900D01*
Y658100D01*
G01X140307Y703600D02*
Y701378D01*
X140460Y700913D01*
X140767Y700603D01*
X141150Y700500D01*
X141533Y700603D01*
X141840Y700913D01*
X141993Y701378D01*
Y703600D01*
G01X143407Y701120D02*
X143637Y700758D01*
X143943Y700552D01*
X144288Y700500D01*
X144595Y700552D01*
X144902Y700810D01*
X145093Y701120D01*
X145132Y701430D01*
X145055Y701792D01*
X144787Y702050D01*
X144518Y702153D01*
X144173D01*
G01X144518D02*
X144748Y702308D01*
X144940Y702567D01*
X145017Y702877D01*
X144940Y703187D01*
X144748Y703445D01*
X144403Y703600D01*
X144058Y703548D01*
X143713Y703342D01*
G01X146698Y700862D02*
X146967Y700603D01*
X147273Y700500D01*
X147580Y700603D01*
X147848Y700913D01*
X148040Y701378D01*
X148117Y701843D01*
Y702412D01*
X148040Y702877D01*
X147848Y703290D01*
X147618Y703497D01*
X147350Y703600D01*
X147043Y703497D01*
X146813Y703290D01*
X146660Y702980D01*
X146583Y702567D01*
X146660Y702205D01*
X146852Y701843D01*
X147082Y701637D01*
X147350Y701585D01*
X147657Y701688D01*
X147887Y701947D01*
X148117Y702412D01*
G01X150450Y703600D02*
X150143Y703497D01*
X149913Y703238D01*
X149760Y702928D01*
X149645Y702515D01*
X149607Y702050D01*
X149645Y701585D01*
X149760Y701172D01*
X149913Y700862D01*
X150143Y700603D01*
X150450Y700500D01*
X150757Y700603D01*
X150987Y700862D01*
X151140Y701172D01*
X151255Y701585D01*
X151293Y702050D01*
X151255Y702515D01*
X151140Y702928D01*
X150987Y703238D01*
X150757Y703497D01*
X150450Y703600D01*
G01X150400Y725050D02*
Y704950D01*
X134600D01*
Y725050D01*
X140250D01*
X142500Y722800D01*
X144750Y725050D01*
X150400D01*
G01X128900Y696100D02*
X135100D01*
Y692900D01*
X128900D01*
Y696100D01*
G01X140807Y735100D02*
Y732878D01*
X140960Y732413D01*
X141267Y732103D01*
X141650Y732000D01*
X142033Y732103D01*
X142340Y732413D01*
X142493Y732878D01*
Y735100D01*
G01X143907Y732620D02*
X144137Y732258D01*
X144443Y732052D01*
X144788Y732000D01*
X145095Y732052D01*
X145402Y732310D01*
X145593Y732620D01*
X145632Y732930D01*
X145555Y733292D01*
X145287Y733550D01*
X145018Y733653D01*
X144673D01*
G01X145018D02*
X145248Y733808D01*
X145440Y734067D01*
X145517Y734377D01*
X145440Y734687D01*
X145248Y734945D01*
X144903Y735100D01*
X144558Y735048D01*
X144213Y734842D01*
G01X147850Y732000D02*
X148118Y732052D01*
X148425Y732207D01*
X148617Y732465D01*
X148693Y732827D01*
X148617Y733188D01*
X148387Y733498D01*
X148042Y733653D01*
X147658D01*
X147428Y733757D01*
X147237Y734015D01*
X147160Y734377D01*
X147275Y734738D01*
X147543Y734997D01*
X147850Y735100D01*
X148157Y734997D01*
X148425Y734738D01*
X148540Y734377D01*
X148463Y734015D01*
X148272Y733757D01*
X148042Y733653D01*
X147658D01*
X147313Y733498D01*
X147083Y733188D01*
X147007Y732827D01*
X147083Y732465D01*
X147275Y732207D01*
X147582Y732052D01*
X147850Y732000D01*
G01X150298Y732362D02*
X150567Y732103D01*
X150873Y732000D01*
X151180Y732103D01*
X151448Y732413D01*
X151640Y732878D01*
X151717Y733343D01*
Y733912D01*
X151640Y734377D01*
X151448Y734790D01*
X151218Y734997D01*
X150950Y735100D01*
X150643Y734997D01*
X150413Y734790D01*
X150260Y734480D01*
X150183Y734067D01*
X150260Y733705D01*
X150452Y733343D01*
X150682Y733137D01*
X150950Y733085D01*
X151257Y733188D01*
X151487Y733447D01*
X151717Y733912D01*
G01X134100Y726900D02*
X127900D01*
Y730100D01*
X134100D01*
Y726900D01*
G01X150900Y756050D02*
Y735950D01*
X135100D01*
Y756050D01*
X140750D01*
X143000Y753800D01*
X145250Y756050D01*
X150900D01*
G01X136000Y775914D02*
Y770314D01*
X150000D01*
Y775914D01*
X136000D01*
G01X133773Y769000D02*
X136013D01*
G01X134800Y770625D02*
Y767375D01*
G01X147087Y769000D02*
X149513D01*
G01X141319Y775083D02*
Y771145D01*
X143287Y773114D01*
X141319Y775083D01*
G01X143681D02*
Y771145D01*
G01X131243Y787031D02*
Y778369D01*
X141757D01*
Y787031D01*
X131243D01*
G01X142227Y766386D02*
X139987D01*
G01X141200Y764761D02*
Y768011D01*
G01X150220Y764728D02*
Y768272D01*
X143134D01*
Y764728D01*
X150142D01*
G01X125400Y779400D02*
Y785600D01*
X128600D01*
Y779400D01*
X125400D01*
G01X133900Y763600D02*
X140100D01*
Y760400D01*
X133900D01*
Y763600D01*
G01X133100Y760400D02*
X126900D01*
Y763600D01*
X133100D01*
Y760400D01*
G01X143400Y777900D02*
Y784100D01*
X146600D01*
Y777900D01*
X143400D01*
G01X129900Y768800D02*
X140100D01*
Y764200D01*
X129900D01*
Y768800D01*
G01X130243Y802831D02*
Y794169D01*
X140757D01*
Y802831D01*
X130243D01*
G01X143227Y807500D02*
X140987D01*
G01X142200Y805875D02*
Y809125D01*
G01X150220Y799728D02*
Y803272D01*
X143134D01*
Y799728D01*
X150142D01*
G01X142727Y791500D02*
X140487D01*
G01X141700Y789875D02*
Y793125D01*
G01X150720Y789728D02*
Y793272D01*
X143634D01*
Y789728D01*
X150642D01*
G01X125400Y792400D02*
Y798600D01*
X128600D01*
Y792400D01*
X125400D01*
G01X143400Y798100D02*
X149600D01*
Y794900D01*
X143400D01*
Y798100D01*
G01Y788100D02*
X149600D01*
Y784900D01*
X143400D01*
Y788100D01*
G01X134400Y792400D02*
X140600D01*
Y789200D01*
X134400D01*
Y792400D01*
G01X125400Y799900D02*
Y806100D01*
X128600D01*
Y799900D01*
X125400D01*
G01X134273Y822500D02*
X136513D01*
G01X135300Y824125D02*
Y820875D01*
G01X146587Y830500D02*
X149013D01*
G01X136500Y829414D02*
X151000D01*
Y823814D01*
X136500D01*
Y829414D01*
G01X141819Y828583D02*
Y824645D01*
X143787Y826614D01*
X141819Y828583D01*
G01X144181D02*
Y824645D01*
G01X129807Y807600D02*
Y805378D01*
X129960Y804913D01*
X130267Y804603D01*
X130650Y804500D01*
X131033Y804603D01*
X131340Y804913D01*
X131493Y805378D01*
Y807600D01*
G01X132907Y805120D02*
X133137Y804758D01*
X133443Y804552D01*
X133788Y804500D01*
X134095Y804552D01*
X134402Y804810D01*
X134593Y805120D01*
X134632Y805430D01*
X134555Y805792D01*
X134287Y806050D01*
X134018Y806153D01*
X133673D01*
G01X134018D02*
X134248Y806308D01*
X134440Y806567D01*
X134517Y806877D01*
X134440Y807187D01*
X134248Y807445D01*
X133903Y807600D01*
X133558Y807548D01*
X133213Y807342D01*
G01X136773Y804500D02*
X136850Y805172D01*
X136965Y805740D01*
X137118Y806257D01*
X137310Y806825D01*
X137617Y807600D01*
X136083D01*
G01X139950Y804500D02*
Y807600D01*
X139490Y806980D01*
G01Y804500D02*
X140410D01*
G01X138545Y820048D02*
X136305D01*
G01X137518Y818423D02*
Y821673D01*
G01X149913Y820000D02*
X147487D01*
G01X146427Y821214D02*
X146327Y818514D01*
Y821614D01*
G01X146720Y818342D02*
Y821886D01*
X139634D01*
Y818342D01*
X146642D01*
G01X134413Y817600D02*
X131987D01*
G01X132927Y816100D02*
X132827Y813400D01*
Y816500D01*
G01X133220Y813228D02*
Y816772D01*
X126134D01*
Y813228D01*
X133142D01*
G01X150100Y804514D02*
X143900D01*
Y807714D01*
X150100D01*
Y804514D01*
G01X143900Y812214D02*
X150100D01*
Y809014D01*
X143900D01*
Y812214D01*
G01X150100Y813514D02*
X143900D01*
Y816714D01*
X150100D01*
Y813514D01*
G01X133100Y818514D02*
X126900D01*
Y821714D01*
X133100D01*
Y818514D01*
G01X141600Y813514D02*
X135400D01*
Y816714D01*
X141600D01*
Y813514D01*
G01X133100Y823014D02*
X126900D01*
Y826214D01*
X133100D01*
Y823014D01*
G01X133913Y837886D02*
X131487D01*
G01X125807Y839386D02*
Y842486D01*
X126573D01*
X126880Y842331D01*
X127110Y842124D01*
X127302Y841814D01*
X127455Y841453D01*
X127493Y840936D01*
X127455Y840419D01*
X127302Y840058D01*
X127110Y839748D01*
X126880Y839541D01*
X126573Y839386D01*
X125807D01*
G01X129022Y841969D02*
X129252Y842279D01*
X129520Y842434D01*
X129827Y842486D01*
X130210Y842383D01*
X130478Y842124D01*
X130555Y841814D01*
X130517Y841504D01*
X130363Y841246D01*
X129597Y840729D01*
X129252Y840368D01*
X129022Y839851D01*
X128945Y839386D01*
X130555D01*
G01X132773D02*
X132850Y840058D01*
X132965Y840626D01*
X133118Y841143D01*
X133310Y841711D01*
X133617Y842486D01*
X132083D01*
G01X135107Y840006D02*
X135337Y839644D01*
X135643Y839438D01*
X135988Y839386D01*
X136295Y839438D01*
X136602Y839696D01*
X136793Y840006D01*
X136832Y840316D01*
X136755Y840678D01*
X136487Y840936D01*
X136218Y841039D01*
X135873D01*
G01X136218D02*
X136448Y841194D01*
X136640Y841453D01*
X136717Y841763D01*
X136640Y842073D01*
X136448Y842331D01*
X136103Y842486D01*
X135758Y842434D01*
X135413Y842228D01*
G01X133927Y835600D02*
X133827Y832900D01*
Y836000D01*
G01X134220Y832728D02*
Y836272D01*
X127134D01*
Y832728D01*
X134142D01*
G01X144400Y835714D02*
X150600D01*
Y832514D01*
X144400D01*
Y835714D01*
G01X142100Y832514D02*
X135900D01*
Y835714D01*
X142100D01*
Y832514D01*
G01X138783Y858400D02*
Y861500D01*
X139703D01*
X140010Y861345D01*
X140240Y860983D01*
X140317Y860570D01*
X140240Y860157D01*
X140048Y859847D01*
X139703Y859692D01*
X138783D01*
G01X143493Y861242D02*
X143263Y861397D01*
X142995Y861500D01*
X142688D01*
X142343Y861345D01*
X142075Y861087D01*
X141883Y860777D01*
X141730Y860260D01*
X141692Y859795D01*
X141768Y859330D01*
X141883Y859020D01*
X142113Y858710D01*
X142382Y858503D01*
X142650Y858400D01*
X142918D01*
X143187Y858503D01*
X143417Y858658D01*
X143608Y858865D01*
G01X145022Y860983D02*
X145252Y861293D01*
X145520Y861448D01*
X145827Y861500D01*
X146210Y861397D01*
X146478Y861138D01*
X146555Y860828D01*
X146517Y860518D01*
X146363Y860260D01*
X145597Y859743D01*
X145252Y859382D01*
X145022Y858865D01*
X144945Y858400D01*
X146555D01*
G01X148007Y859020D02*
X148237Y858658D01*
X148543Y858452D01*
X148888Y858400D01*
X149195Y858452D01*
X149502Y858710D01*
X149693Y859020D01*
X149732Y859330D01*
X149655Y859692D01*
X149387Y859950D01*
X149118Y860053D01*
X148773D01*
G01X149118D02*
X149348Y860208D01*
X149540Y860467D01*
X149617Y860777D01*
X149540Y861087D01*
X149348Y861345D01*
X149003Y861500D01*
X148658Y861448D01*
X148313Y861242D01*
G01X138731Y878500D02*
Y867731D01*
X143731Y862731D01*
G01D02*
X180069D01*
Y878500D01*
G01Y888300D02*
Y904069D01*
X143731D01*
X138731Y899069D01*
Y888300D01*
G01X150600Y983400D02*
X144400D01*
Y986600D01*
X150600D01*
Y983400D01*
G01X142900Y982100D02*
X149100D01*
Y978900D01*
X142900D01*
Y982100D01*
G01X144400Y990600D02*
X150600D01*
Y987400D01*
X144400D01*
Y990600D01*
G01X143600Y989100D02*
Y982900D01*
X140400D01*
Y989100D01*
X143600D01*
G01X147582Y991049D02*
X141382D01*
Y994249D01*
X147582D01*
Y991049D01*
G01X134882Y992549D02*
Y998749D01*
X138082D01*
Y992549D01*
X134882D01*
G01X135573Y1129700D02*
X137813D01*
G01X136600Y1131325D02*
Y1128075D01*
G01X148087Y1131000D02*
X150513D01*
G01X139127Y1125800D02*
X136887D01*
G01X138100Y1124175D02*
Y1127425D01*
G01X150413Y1128500D02*
X147987D01*
G01X136500Y1137800D02*
Y1132200D01*
X150500D01*
Y1137800D01*
X136500D01*
G01X141819Y1136969D02*
Y1133031D01*
X143787Y1135000D01*
X141819Y1136969D01*
G01X144181D02*
Y1133031D01*
G01X130243Y1150331D02*
Y1141669D01*
X140757D01*
Y1150331D01*
X130243D01*
G01X142727Y1151500D02*
X140487D01*
G01X141700Y1149875D02*
Y1153125D01*
G01X150720Y1149228D02*
Y1152772D01*
X143634D01*
Y1149228D01*
X150642D01*
G01X140000Y1138773D02*
Y1141013D01*
G01X138375Y1139800D02*
X141625D01*
G01X150720Y1139728D02*
Y1143272D01*
X143634D01*
Y1139728D01*
X150642D01*
G01X146427Y1129600D02*
X146327Y1126900D01*
Y1130000D01*
G01X146720Y1126728D02*
Y1130272D01*
X139634D01*
Y1126728D01*
X146642D01*
G01X125400Y1143900D02*
Y1150100D01*
X128600D01*
Y1143900D01*
X125400D01*
G01X130600Y1133600D02*
Y1127400D01*
X127400D01*
Y1133600D01*
X130600D01*
G01X134600D02*
Y1127400D01*
X131400D01*
Y1133600D01*
X134600D01*
G01X143900Y1148000D02*
X150100D01*
Y1144800D01*
X143900D01*
Y1148000D01*
G01X124400Y1139800D02*
X134600D01*
Y1135200D01*
X124400D01*
Y1139800D01*
G01X130243Y1166331D02*
Y1157669D01*
X140757D01*
Y1166331D01*
X130243D01*
G01X128307Y1172500D02*
Y1175600D01*
X129073D01*
X129380Y1175445D01*
X129610Y1175238D01*
X129802Y1174928D01*
X129955Y1174567D01*
X129993Y1174050D01*
X129955Y1173533D01*
X129802Y1173172D01*
X129610Y1172862D01*
X129380Y1172655D01*
X129073Y1172500D01*
X128307D01*
G01X131522Y1175083D02*
X131752Y1175393D01*
X132020Y1175548D01*
X132327Y1175600D01*
X132710Y1175497D01*
X132978Y1175238D01*
X133055Y1174928D01*
X133017Y1174618D01*
X132863Y1174360D01*
X132097Y1173843D01*
X131752Y1173482D01*
X131522Y1172965D01*
X131445Y1172500D01*
X133055D01*
G01X134622Y1173792D02*
X134890Y1174153D01*
X135120Y1174360D01*
X135427Y1174463D01*
X135695Y1174360D01*
X135887Y1174153D01*
X136040Y1173843D01*
X136078Y1173482D01*
X136040Y1173172D01*
X135887Y1172862D01*
X135657Y1172603D01*
X135388Y1172500D01*
X135082Y1172603D01*
X134813Y1172913D01*
X134660Y1173378D01*
X134622Y1173895D01*
X134698Y1174567D01*
X134813Y1174928D01*
X135005Y1175290D01*
X135273Y1175548D01*
X135542Y1175600D01*
X135810Y1175497D01*
X136002Y1175238D01*
G01X138450Y1172500D02*
X138718Y1172552D01*
X139025Y1172707D01*
X139217Y1172965D01*
X139293Y1173327D01*
X139217Y1173688D01*
X138987Y1173998D01*
X138642Y1174153D01*
X138258D01*
X138028Y1174257D01*
X137837Y1174515D01*
X137760Y1174877D01*
X137875Y1175238D01*
X138143Y1175497D01*
X138450Y1175600D01*
X138757Y1175497D01*
X139025Y1175238D01*
X139140Y1174877D01*
X139063Y1174515D01*
X138872Y1174257D01*
X138642Y1174153D01*
X138258D01*
X137913Y1173998D01*
X137683Y1173688D01*
X137607Y1173327D01*
X137683Y1172965D01*
X137875Y1172707D01*
X138182Y1172552D01*
X138450Y1172500D01*
G01X150100Y1158900D02*
X143900D01*
Y1162100D01*
X150100D01*
Y1158900D01*
G01X125400Y1157900D02*
Y1164100D01*
X128600D01*
Y1157900D01*
X125400D01*
G01X143900Y1157600D02*
X150100D01*
Y1154400D01*
X143900D01*
Y1157600D01*
G01Y1166600D02*
X150100D01*
Y1163400D01*
X143900D01*
Y1166600D01*
G01Y1171100D02*
X150100D01*
Y1167900D01*
X143900D01*
Y1171100D01*
G01X134400Y1171600D02*
X140600D01*
Y1168400D01*
X134400D01*
Y1171600D01*
G01Y1155600D02*
X140600D01*
Y1152400D01*
X134400D01*
Y1155600D01*
G01X136500Y1192800D02*
Y1187200D01*
X150500D01*
Y1192800D01*
X136500D01*
G01X133773Y1186500D02*
X136013D01*
G01X134800Y1188125D02*
Y1184875D01*
G01X147587Y1186000D02*
X150013D01*
G01X141819Y1191969D02*
Y1188031D01*
X143787Y1190000D01*
X141819Y1191969D01*
G01X144181D02*
Y1188031D01*
G01X143727Y1180900D02*
X141487D01*
G01X142700Y1179275D02*
Y1182525D01*
G01X150720Y1181728D02*
Y1185272D01*
X143634D01*
Y1181728D01*
X150642D01*
G01X135413Y1181000D02*
X132987D01*
G01X133427Y1179600D02*
X133327Y1176900D01*
Y1180000D01*
G01X133720Y1176728D02*
Y1180272D01*
X126634D01*
Y1176728D01*
X133642D01*
G01X143900Y1175600D02*
X150100D01*
Y1172400D01*
X143900D01*
Y1175600D01*
G01X150100Y1176900D02*
X143900D01*
Y1180100D01*
X150100D01*
Y1176900D01*
G01X133100Y1181900D02*
X126900D01*
Y1185100D01*
X133100D01*
Y1181900D01*
G01X136900Y1178900D02*
Y1185100D01*
X140100D01*
Y1178900D01*
X136900D01*
G01X133100Y1186400D02*
X126900D01*
Y1189600D01*
X133100D01*
Y1186400D01*
G01X135613Y1200800D02*
X133187D01*
G01X125907Y1202450D02*
Y1205550D01*
X126673D01*
X126980Y1205395D01*
X127210Y1205188D01*
X127402Y1204878D01*
X127555Y1204517D01*
X127593Y1204000D01*
X127555Y1203483D01*
X127402Y1203122D01*
X127210Y1202812D01*
X126980Y1202605D01*
X126673Y1202450D01*
X125907D01*
G01X129122Y1205033D02*
X129352Y1205343D01*
X129620Y1205498D01*
X129927Y1205550D01*
X130310Y1205447D01*
X130578Y1205188D01*
X130655Y1204878D01*
X130617Y1204568D01*
X130463Y1204310D01*
X129697Y1203793D01*
X129352Y1203432D01*
X129122Y1202915D01*
X129045Y1202450D01*
X130655D01*
G01X132222Y1203742D02*
X132490Y1204103D01*
X132720Y1204310D01*
X133027Y1204413D01*
X133295Y1204310D01*
X133487Y1204103D01*
X133640Y1203793D01*
X133678Y1203432D01*
X133640Y1203122D01*
X133487Y1202812D01*
X133257Y1202553D01*
X132988Y1202450D01*
X132682Y1202553D01*
X132413Y1202863D01*
X132260Y1203328D01*
X132222Y1203845D01*
X132298Y1204517D01*
X132413Y1204878D01*
X132605Y1205240D01*
X132873Y1205498D01*
X133142Y1205550D01*
X133410Y1205447D01*
X133602Y1205188D01*
G01X135973Y1202450D02*
X136050Y1203122D01*
X136165Y1203690D01*
X136318Y1204207D01*
X136510Y1204775D01*
X136817Y1205550D01*
X135283D01*
G01X132927Y1199100D02*
X132827Y1196400D01*
Y1199500D01*
G01X133220Y1196228D02*
Y1199772D01*
X126134D01*
Y1196228D01*
X133142D01*
G01X144400Y1199100D02*
X150600D01*
Y1195900D01*
X144400D01*
Y1199100D01*
G01X142100Y1195900D02*
X135900D01*
Y1199100D01*
X142100D01*
Y1195900D01*
G01X187950Y17500D02*
G03I-9450J0D01*
G01X151587Y64000D02*
X154013D01*
G01X149000Y66700D02*
Y61300D01*
G01X149500D02*
Y66700D01*
G01X150000D02*
Y61300D01*
G01X153000Y55727D02*
Y53487D01*
G01X154625Y54700D02*
X151375D01*
G01X153000Y59913D02*
Y57487D01*
G01X151807Y66000D02*
Y69100D01*
X152573D01*
X152880Y68945D01*
X153110Y68738D01*
X153302Y68428D01*
X153455Y68067D01*
X153493Y67550D01*
X153455Y67033D01*
X153302Y66672D01*
X153110Y66362D01*
X152880Y66155D01*
X152573Y66000D01*
X151807D01*
G01X155750D02*
Y69100D01*
X155290Y68480D01*
G01Y66000D02*
X156210D01*
G01X159310D02*
Y69100D01*
X157892Y66878D01*
X159808D01*
G01X161107Y66620D02*
X161337Y66258D01*
X161643Y66052D01*
X161988Y66000D01*
X162295Y66052D01*
X162602Y66310D01*
X162793Y66620D01*
X162832Y66930D01*
X162755Y67292D01*
X162487Y67550D01*
X162218Y67653D01*
X161873D01*
G01X162218D02*
X162448Y67808D01*
X162640Y68067D01*
X162717Y68377D01*
X162640Y68687D01*
X162448Y68945D01*
X162103Y69100D01*
X161758Y69048D01*
X161413Y68842D01*
G01X151807Y73600D02*
Y71378D01*
X151960Y70913D01*
X152267Y70603D01*
X152650Y70500D01*
X153033Y70603D01*
X153340Y70913D01*
X153493Y71378D01*
Y73600D01*
G01X154907Y71120D02*
X155137Y70758D01*
X155443Y70552D01*
X155788Y70500D01*
X156095Y70552D01*
X156402Y70810D01*
X156593Y71120D01*
X156632Y71430D01*
X156555Y71792D01*
X156287Y72050D01*
X156018Y72153D01*
X155673D01*
G01X156018D02*
X156248Y72308D01*
X156440Y72567D01*
X156517Y72877D01*
X156440Y73187D01*
X156248Y73445D01*
X155903Y73600D01*
X155558Y73548D01*
X155213Y73342D01*
G01X158773Y70500D02*
X158850Y71172D01*
X158965Y71740D01*
X159118Y72257D01*
X159310Y72825D01*
X159617Y73600D01*
X158083D01*
G01X161107Y70965D02*
X161337Y70707D01*
X161605Y70552D01*
X161950Y70500D01*
X162295Y70603D01*
X162563Y70810D01*
X162755Y71172D01*
X162793Y71585D01*
X162717Y71998D01*
X162525Y72257D01*
X162257Y72463D01*
X161988Y72515D01*
X161720Y72463D01*
X161375Y72257D01*
X161490Y73600D01*
X162525D01*
G01X153913Y78500D02*
X151487D01*
G01X152307Y81000D02*
Y84100D01*
X153073D01*
X153380Y83945D01*
X153610Y83738D01*
X153802Y83428D01*
X153955Y83067D01*
X153993Y82550D01*
X153955Y82033D01*
X153802Y81672D01*
X153610Y81362D01*
X153380Y81155D01*
X153073Y81000D01*
X152307D01*
G01X155522Y83583D02*
X155752Y83893D01*
X156020Y84048D01*
X156327Y84100D01*
X156710Y83997D01*
X156978Y83738D01*
X157055Y83428D01*
X157017Y83118D01*
X156863Y82860D01*
X156097Y82343D01*
X155752Y81982D01*
X155522Y81465D01*
X155445Y81000D01*
X157055D01*
G01X159350D02*
X159618Y81052D01*
X159925Y81207D01*
X160117Y81465D01*
X160193Y81827D01*
X160117Y82188D01*
X159887Y82498D01*
X159542Y82653D01*
X159158D01*
X158928Y82757D01*
X158737Y83015D01*
X158660Y83377D01*
X158775Y83738D01*
X159043Y83997D01*
X159350Y84100D01*
X159657Y83997D01*
X159925Y83738D01*
X160040Y83377D01*
X159963Y83015D01*
X159772Y82757D01*
X159542Y82653D01*
X159158D01*
X158813Y82498D01*
X158583Y82188D01*
X158507Y81827D01*
X158583Y81465D01*
X158775Y81207D01*
X159082Y81052D01*
X159350Y81000D01*
G01X161722Y83583D02*
X161952Y83893D01*
X162220Y84048D01*
X162527Y84100D01*
X162910Y83997D01*
X163178Y83738D01*
X163255Y83428D01*
X163217Y83118D01*
X163063Y82860D01*
X162297Y82343D01*
X161952Y81982D01*
X161722Y81465D01*
X161645Y81000D01*
X163255D01*
G01X150427Y80942D02*
X150327Y78242D01*
Y81342D01*
G01X156307Y108000D02*
Y111100D01*
X157073D01*
X157380Y110945D01*
X157610Y110738D01*
X157802Y110428D01*
X157955Y110067D01*
X157993Y109550D01*
X157955Y109033D01*
X157802Y108672D01*
X157610Y108362D01*
X157380Y108155D01*
X157073Y108000D01*
X156307D01*
G01X159522Y110583D02*
X159752Y110893D01*
X160020Y111048D01*
X160327Y111100D01*
X160710Y110997D01*
X160978Y110738D01*
X161055Y110428D01*
X161017Y110118D01*
X160863Y109860D01*
X160097Y109343D01*
X159752Y108982D01*
X159522Y108465D01*
X159445Y108000D01*
X161055D01*
G01X163350D02*
X163618Y108052D01*
X163925Y108207D01*
X164117Y108465D01*
X164193Y108827D01*
X164117Y109188D01*
X163887Y109498D01*
X163542Y109653D01*
X163158D01*
X162928Y109757D01*
X162737Y110015D01*
X162660Y110377D01*
X162775Y110738D01*
X163043Y110997D01*
X163350Y111100D01*
X163657Y110997D01*
X163925Y110738D01*
X164040Y110377D01*
X163963Y110015D01*
X163772Y109757D01*
X163542Y109653D01*
X163158D01*
X162813Y109498D01*
X162583Y109188D01*
X162507Y108827D01*
X162583Y108465D01*
X162775Y108207D01*
X163082Y108052D01*
X163350Y108000D01*
G01X166910D02*
Y111100D01*
X165492Y108878D01*
X167408D01*
G01X153913Y94500D02*
X151487D01*
G01X151807Y95500D02*
Y98600D01*
X152573D01*
X152880Y98445D01*
X153110Y98238D01*
X153302Y97928D01*
X153455Y97567D01*
X153493Y97050D01*
X153455Y96533D01*
X153302Y96172D01*
X153110Y95862D01*
X152880Y95655D01*
X152573Y95500D01*
X151807D01*
G01X155022Y98083D02*
X155252Y98393D01*
X155520Y98548D01*
X155827Y98600D01*
X156210Y98497D01*
X156478Y98238D01*
X156555Y97928D01*
X156517Y97618D01*
X156363Y97360D01*
X155597Y96843D01*
X155252Y96482D01*
X155022Y95965D01*
X154945Y95500D01*
X156555D01*
G01X158850D02*
X159118Y95552D01*
X159425Y95707D01*
X159617Y95965D01*
X159693Y96327D01*
X159617Y96688D01*
X159387Y96998D01*
X159042Y97153D01*
X158658D01*
X158428Y97257D01*
X158237Y97515D01*
X158160Y97877D01*
X158275Y98238D01*
X158543Y98497D01*
X158850Y98600D01*
X159157Y98497D01*
X159425Y98238D01*
X159540Y97877D01*
X159463Y97515D01*
X159272Y97257D01*
X159042Y97153D01*
X158658D01*
X158313Y96998D01*
X158083Y96688D01*
X158007Y96327D01*
X158083Y95965D01*
X158275Y95707D01*
X158582Y95552D01*
X158850Y95500D01*
G01X161950D02*
Y98600D01*
X161490Y97980D01*
G01Y95500D02*
X162410D01*
G01X150427Y95100D02*
X150327Y92400D01*
Y95500D01*
G01X151787Y119442D02*
X154213D01*
G01X156307Y118000D02*
Y121100D01*
X157073D01*
X157380Y120945D01*
X157610Y120738D01*
X157802Y120428D01*
X157955Y120067D01*
X157993Y119550D01*
X157955Y119033D01*
X157802Y118672D01*
X157610Y118362D01*
X157380Y118155D01*
X157073Y118000D01*
X156307D01*
G01X160250D02*
Y121100D01*
X159790Y120480D01*
G01Y118000D02*
X160710D01*
G01X163810D02*
Y121100D01*
X162392Y118878D01*
X164308D01*
G01X166450Y118000D02*
Y121100D01*
X165990Y120480D01*
G01Y118000D02*
X166910D01*
G01X149500Y122042D02*
Y116642D01*
G01X150000D02*
Y122042D01*
G01X150500D02*
Y116642D01*
G01X147485Y134462D02*
X183823D01*
Y150231D01*
G01X154882Y270328D02*
X161082D01*
Y267128D01*
X154882D01*
Y270328D01*
G01X161082Y262128D02*
X154882D01*
Y265328D01*
X161082D01*
Y262128D01*
G01X152900Y286900D02*
Y293100D01*
X156100D01*
Y286900D01*
X152900D01*
G01X157458Y276128D02*
X151258D01*
Y279328D01*
X157458D01*
Y276128D01*
G01X164758Y285328D02*
X170958D01*
Y282128D01*
X164758D01*
Y285328D01*
G01X157400Y293600D02*
X163600D01*
Y290400D01*
X157400D01*
Y293600D01*
G01X163600Y286400D02*
X157400D01*
Y289600D01*
X163600D01*
Y286400D01*
G01X151258Y284328D02*
X157458D01*
Y281128D01*
X151258D01*
Y284328D01*
G01X165400Y286900D02*
Y293100D01*
X168600D01*
Y286900D01*
X165400D01*
G01X148783Y333300D02*
Y336400D01*
X149703D01*
X150010Y336245D01*
X150240Y335883D01*
X150317Y335470D01*
X150240Y335057D01*
X150048Y334747D01*
X149703Y334592D01*
X148783D01*
G01X153493Y336142D02*
X153263Y336297D01*
X152995Y336400D01*
X152688D01*
X152343Y336245D01*
X152075Y335987D01*
X151883Y335677D01*
X151730Y335160D01*
X151692Y334695D01*
X151768Y334230D01*
X151883Y333920D01*
X152113Y333610D01*
X152382Y333403D01*
X152650Y333300D01*
X152918D01*
X153187Y333403D01*
X153417Y333558D01*
X153608Y333765D01*
G01X155022Y335883D02*
X155252Y336193D01*
X155520Y336348D01*
X155827Y336400D01*
X156210Y336297D01*
X156478Y336038D01*
X156555Y335728D01*
X156517Y335418D01*
X156363Y335160D01*
X155597Y334643D01*
X155252Y334282D01*
X155022Y333765D01*
X154945Y333300D01*
X156555D01*
G01X158198Y333662D02*
X158467Y333403D01*
X158773Y333300D01*
X159080Y333403D01*
X159348Y333713D01*
X159540Y334178D01*
X159617Y334643D01*
Y335212D01*
X159540Y335677D01*
X159348Y336090D01*
X159118Y336297D01*
X158850Y336400D01*
X158543Y336297D01*
X158313Y336090D01*
X158160Y335780D01*
X158083Y335367D01*
X158160Y335005D01*
X158352Y334643D01*
X158582Y334437D01*
X158850Y334385D01*
X159157Y334488D01*
X159387Y334747D01*
X159617Y335212D01*
G01X159569Y363000D02*
Y373769D01*
X154569Y378769D01*
G01X151743Y393331D02*
Y384669D01*
X162257D01*
Y393331D01*
X151743D01*
G01X174600Y386700D02*
X164400D01*
Y391300D01*
X174600D01*
Y386700D01*
G01X153307Y404000D02*
Y407100D01*
X154073D01*
X154380Y406945D01*
X154610Y406738D01*
X154802Y406428D01*
X154955Y406067D01*
X154993Y405550D01*
X154955Y405033D01*
X154802Y404672D01*
X154610Y404362D01*
X154380Y404155D01*
X154073Y404000D01*
X153307D01*
G01X157250D02*
Y407100D01*
X156790Y406480D01*
G01Y404000D02*
X157710D01*
G01X159507Y404620D02*
X159737Y404258D01*
X160043Y404052D01*
X160388Y404000D01*
X160695Y404052D01*
X161002Y404310D01*
X161193Y404620D01*
X161232Y404930D01*
X161155Y405292D01*
X160887Y405550D01*
X160618Y405653D01*
X160273D01*
G01X160618D02*
X160848Y405808D01*
X161040Y406067D01*
X161117Y406377D01*
X161040Y406687D01*
X160848Y406945D01*
X160503Y407100D01*
X160158Y407048D01*
X159813Y406842D01*
G01X162798Y404362D02*
X163067Y404103D01*
X163373Y404000D01*
X163680Y404103D01*
X163948Y404413D01*
X164140Y404878D01*
X164217Y405343D01*
Y405912D01*
X164140Y406377D01*
X163948Y406790D01*
X163718Y406997D01*
X163450Y407100D01*
X163143Y406997D01*
X162913Y406790D01*
X162760Y406480D01*
X162683Y406067D01*
X162760Y405705D01*
X162952Y405343D01*
X163182Y405137D01*
X163450Y405085D01*
X163757Y405188D01*
X163987Y405447D01*
X164217Y405912D01*
G01X150500Y409928D02*
Y404528D01*
G01X150000D02*
Y409928D01*
G01X149500D02*
Y404528D01*
G01X152407Y397500D02*
Y395278D01*
X152560Y394813D01*
X152867Y394503D01*
X153250Y394400D01*
X153633Y394503D01*
X153940Y394813D01*
X154093Y395278D01*
Y397500D01*
G01X156810Y394400D02*
Y397500D01*
X155392Y395278D01*
X157308D01*
G01X159450Y397500D02*
X159143Y397397D01*
X158913Y397138D01*
X158760Y396828D01*
X158645Y396415D01*
X158607Y395950D01*
X158645Y395485D01*
X158760Y395072D01*
X158913Y394762D01*
X159143Y394503D01*
X159450Y394400D01*
X159757Y394503D01*
X159987Y394762D01*
X160140Y395072D01*
X160255Y395485D01*
X160293Y395950D01*
X160255Y396415D01*
X160140Y396828D01*
X159987Y397138D01*
X159757Y397397D01*
X159450Y397500D01*
G01X162473Y394400D02*
X162550Y395072D01*
X162665Y395640D01*
X162818Y396157D01*
X163010Y396725D01*
X163317Y397500D01*
X161783D01*
G01X154323Y430450D02*
X151897D01*
G01X147807Y421500D02*
Y424600D01*
X148573D01*
X148880Y424445D01*
X149110Y424238D01*
X149302Y423928D01*
X149455Y423567D01*
X149493Y423050D01*
X149455Y422533D01*
X149302Y422172D01*
X149110Y421862D01*
X148880Y421655D01*
X148573Y421500D01*
X147807D01*
G01X151022Y424083D02*
X151252Y424393D01*
X151520Y424548D01*
X151827Y424600D01*
X152210Y424497D01*
X152478Y424238D01*
X152555Y423928D01*
X152517Y423618D01*
X152363Y423360D01*
X151597Y422843D01*
X151252Y422482D01*
X151022Y421965D01*
X150945Y421500D01*
X152555D01*
G01X154773D02*
X154850Y422172D01*
X154965Y422740D01*
X155118Y423257D01*
X155310Y423825D01*
X155617Y424600D01*
X154083D01*
G01X157107Y421965D02*
X157337Y421707D01*
X157605Y421552D01*
X157950Y421500D01*
X158295Y421603D01*
X158563Y421810D01*
X158755Y422172D01*
X158793Y422585D01*
X158717Y422998D01*
X158525Y423257D01*
X158257Y423463D01*
X157988Y423515D01*
X157720Y423463D01*
X157375Y423257D01*
X157490Y424600D01*
X158525D01*
G01X150427Y429100D02*
X150327Y426400D01*
Y429500D01*
G01X152517Y412720D02*
Y415820D01*
X153283D01*
X153590Y415665D01*
X153820Y415458D01*
X154012Y415148D01*
X154165Y414787D01*
X154203Y414270D01*
X154165Y413753D01*
X154012Y413392D01*
X153820Y413082D01*
X153590Y412875D01*
X153283Y412720D01*
X152517D01*
G01X155732Y415303D02*
X155962Y415613D01*
X156230Y415768D01*
X156537Y415820D01*
X156920Y415717D01*
X157188Y415458D01*
X157265Y415148D01*
X157227Y414838D01*
X157073Y414580D01*
X156307Y414063D01*
X155962Y413702D01*
X155732Y413185D01*
X155655Y412720D01*
X157265D01*
G01X159483D02*
X159560Y413392D01*
X159675Y413960D01*
X159828Y414477D01*
X160020Y415045D01*
X160327Y415820D01*
X158793D01*
G01X161932Y414012D02*
X162200Y414373D01*
X162430Y414580D01*
X162737Y414683D01*
X163005Y414580D01*
X163197Y414373D01*
X163350Y414063D01*
X163388Y413702D01*
X163350Y413392D01*
X163197Y413082D01*
X162967Y412823D01*
X162698Y412720D01*
X162392Y412823D01*
X162123Y413133D01*
X161970Y413598D01*
X161932Y414115D01*
X162008Y414787D01*
X162123Y415148D01*
X162315Y415510D01*
X162583Y415768D01*
X162852Y415820D01*
X163120Y415717D01*
X163312Y415458D01*
G01X150427Y414828D02*
X150327Y412128D01*
Y415228D01*
G01X154903Y462420D02*
Y464920D01*
X155437D01*
X155650Y464795D01*
X155810Y464628D01*
X155943Y464378D01*
X156050Y464087D01*
X156077Y463670D01*
X156050Y463253D01*
X155943Y462962D01*
X155810Y462712D01*
X155650Y462545D01*
X155437Y462420D01*
X154903D01*
G01X157690D02*
Y464920D01*
X157370Y464420D01*
G01Y462420D02*
X158010D01*
G01X159303Y462920D02*
X159463Y462628D01*
X159677Y462462D01*
X159917Y462420D01*
X160130Y462462D01*
X160343Y462670D01*
X160477Y462920D01*
X160503Y463170D01*
X160450Y463462D01*
X160263Y463670D01*
X160077Y463753D01*
X159837D01*
G01X160077D02*
X160237Y463878D01*
X160370Y464087D01*
X160423Y464337D01*
X160370Y464587D01*
X160237Y464795D01*
X159997Y464920D01*
X159757Y464878D01*
X159517Y464712D01*
G01X162037Y462420D02*
X162090Y462962D01*
X162170Y463420D01*
X162277Y463837D01*
X162410Y464295D01*
X162623Y464920D01*
X161557D01*
G01X150000Y460300D02*
Y465700D01*
G01X149500D02*
Y460300D01*
G01X152117Y457970D02*
Y461070D01*
X152883D01*
X153190Y460915D01*
X153420Y460708D01*
X153612Y460398D01*
X153765Y460037D01*
X153803Y459520D01*
X153765Y459003D01*
X153612Y458642D01*
X153420Y458332D01*
X153190Y458125D01*
X152883Y457970D01*
X152117D01*
G01X155332Y460553D02*
X155562Y460863D01*
X155830Y461018D01*
X156137Y461070D01*
X156520Y460967D01*
X156788Y460708D01*
X156865Y460398D01*
X156827Y460088D01*
X156673Y459830D01*
X155907Y459313D01*
X155562Y458952D01*
X155332Y458435D01*
X155255Y457970D01*
X156865D01*
G01X159083D02*
X159160Y458642D01*
X159275Y459210D01*
X159428Y459727D01*
X159620Y460295D01*
X159927Y461070D01*
X158393D01*
G01X162260Y457970D02*
X162528Y458022D01*
X162835Y458177D01*
X163027Y458435D01*
X163103Y458797D01*
X163027Y459158D01*
X162797Y459468D01*
X162452Y459623D01*
X162068D01*
X161838Y459727D01*
X161647Y459985D01*
X161570Y460347D01*
X161685Y460708D01*
X161953Y460967D01*
X162260Y461070D01*
X162567Y460967D01*
X162835Y460708D01*
X162950Y460347D01*
X162873Y459985D01*
X162682Y459727D01*
X162452Y459623D01*
X162068D01*
X161723Y459468D01*
X161493Y459158D01*
X161417Y458797D01*
X161493Y458435D01*
X161685Y458177D01*
X161992Y458022D01*
X162260Y457970D01*
G01X148975Y488600D02*
X155175D01*
Y485400D01*
X148975D01*
Y488600D01*
G01X149050Y493600D02*
X155250D01*
Y490400D01*
X149050D01*
Y493600D01*
G01Y498600D02*
X155250D01*
Y495400D01*
X149050D01*
Y498600D01*
G01Y503600D02*
X155250D01*
Y500400D01*
X149050D01*
Y503600D01*
G01Y508600D02*
X155250D01*
Y505400D01*
X149050D01*
Y508600D01*
G01Y513600D02*
X155250D01*
Y510400D01*
X149050D01*
Y513600D01*
G01Y518600D02*
X155250D01*
Y515400D01*
X149050D01*
Y518600D01*
G01Y523600D02*
X155250D01*
Y520400D01*
X149050D01*
Y523600D01*
G01X167947Y504650D02*
X168000Y505192D01*
X168080Y505650D01*
X168187Y506067D01*
X168320Y506525D01*
X168533Y507150D01*
X167467D01*
G01X161092Y512407D02*
X161383Y512220D01*
X161550Y512060D01*
X161633Y511847D01*
X161550Y511660D01*
X161383Y511527D01*
X161133Y511420D01*
X160842Y511393D01*
X160592Y511420D01*
X160342Y511527D01*
X160133Y511687D01*
X160050Y511873D01*
X160133Y512087D01*
X160383Y512273D01*
X160758Y512380D01*
X161175Y512407D01*
X161717Y512353D01*
X162008Y512273D01*
X162300Y512140D01*
X162508Y511953D01*
X162550Y511767D01*
X162467Y511580D01*
X162258Y511447D01*
G01X162600Y515000D02*
X160600D01*
G01X165126Y524000D02*
Y525874D01*
X167000D01*
G01Y510126D02*
X165126D01*
Y512000D01*
G01X173100Y536600D02*
Y530400D01*
X169900D01*
Y536600D01*
X173100D01*
G01X168100D02*
Y530400D01*
X164900D01*
Y536600D01*
X168100D01*
G01X173100Y543600D02*
Y537400D01*
X169900D01*
Y543600D01*
X173100D01*
G01X168100D02*
Y537400D01*
X164900D01*
Y543600D01*
X168100D01*
G01X149050Y528600D02*
X155250D01*
Y525400D01*
X149050D01*
Y528600D01*
G01Y533600D02*
X155250D01*
Y530400D01*
X149050D01*
Y533600D01*
G01Y538600D02*
X155250D01*
Y535400D01*
X149050D01*
Y538600D01*
G01X148975Y543600D02*
X155175D01*
Y540400D01*
X148975D01*
Y543600D01*
G01X162743Y528873D02*
X162903Y529123D01*
X163090Y529248D01*
X163303Y529290D01*
X163570Y529207D01*
X163757Y528998D01*
X163810Y528748D01*
X163783Y528498D01*
X163677Y528290D01*
X163143Y527873D01*
X162903Y527582D01*
X162743Y527165D01*
X162690Y526790D01*
X163810D01*
G01X165770D02*
Y529290D01*
X164783Y527498D01*
X166117D01*
G01X159345Y551500D02*
Y554600D01*
G01X160955D02*
Y551500D01*
G01Y553050D02*
X159345D01*
G01X163710Y551500D02*
Y554600D01*
X162292Y552378D01*
X164208D01*
G01X174600Y661900D02*
X168400D01*
Y665100D01*
X174600D01*
Y661900D01*
G01Y657900D02*
X168400D01*
Y661100D01*
X174600D01*
Y657900D01*
G01Y649900D02*
X168400D01*
Y653100D01*
X174600D01*
Y649900D01*
G01X168400Y690100D02*
X174600D01*
Y686900D01*
X168400D01*
Y690100D01*
G01Y686100D02*
X174600D01*
Y682900D01*
X168400D01*
Y686100D01*
G01Y682100D02*
X174600D01*
Y678900D01*
X168400D01*
Y682100D01*
G01Y678100D02*
X174600D01*
Y674900D01*
X168400D01*
Y678100D01*
G01Y674100D02*
X174600D01*
Y670900D01*
X168400D01*
Y674100D01*
G01Y670100D02*
X174600D01*
Y666900D01*
X168400D01*
Y670100D01*
G01X168600Y704400D02*
X162400D01*
Y707600D01*
X168600D01*
Y704400D01*
G01X168400Y698100D02*
X174600D01*
Y694900D01*
X168400D01*
Y698100D01*
G01Y694100D02*
X174600D01*
Y690900D01*
X168400D01*
Y694100D01*
G01X168600Y731400D02*
X162400D01*
Y734600D01*
X168600D01*
Y731400D01*
G01X162400Y721600D02*
X168600D01*
Y718400D01*
X162400D01*
Y721600D01*
G01Y714600D02*
X168600D01*
Y711400D01*
X162400D01*
Y714600D01*
G01X153600Y727400D02*
X147400D01*
Y730600D01*
X153600D01*
Y727400D01*
G01X162400Y748600D02*
X168600D01*
Y745400D01*
X162400D01*
Y748600D01*
G01Y741600D02*
X168600D01*
Y738400D01*
X162400D01*
Y741600D01*
G01Y755600D02*
X168600D01*
Y752400D01*
X162400D01*
Y755600D01*
G01X151807Y768000D02*
Y771100D01*
X152573D01*
X152880Y770945D01*
X153110Y770738D01*
X153302Y770428D01*
X153455Y770067D01*
X153493Y769550D01*
X153455Y769033D01*
X153302Y768672D01*
X153110Y768362D01*
X152880Y768155D01*
X152573Y768000D01*
X151807D01*
G01X155750D02*
Y771100D01*
X155290Y770480D01*
G01Y768000D02*
X156210D01*
G01X158007Y768620D02*
X158237Y768258D01*
X158543Y768052D01*
X158888Y768000D01*
X159195Y768052D01*
X159502Y768310D01*
X159693Y768620D01*
X159732Y768930D01*
X159655Y769292D01*
X159387Y769550D01*
X159118Y769653D01*
X158773D01*
G01X159118D02*
X159348Y769808D01*
X159540Y770067D01*
X159617Y770377D01*
X159540Y770687D01*
X159348Y770945D01*
X159003Y771100D01*
X158658Y771048D01*
X158313Y770842D01*
G01X161107Y768465D02*
X161337Y768207D01*
X161605Y768052D01*
X161950Y768000D01*
X162295Y768103D01*
X162563Y768310D01*
X162755Y768672D01*
X162793Y769085D01*
X162717Y769498D01*
X162525Y769757D01*
X162257Y769963D01*
X161988Y770015D01*
X161720Y769963D01*
X161375Y769757D01*
X161490Y771100D01*
X162525D01*
G01X149500Y770414D02*
Y775814D01*
G01X149000D02*
Y770414D01*
G01X153413Y766386D02*
X150987D01*
G01X155807Y763386D02*
Y766486D01*
X156573D01*
X156880Y766331D01*
X157110Y766124D01*
X157302Y765814D01*
X157455Y765453D01*
X157493Y764936D01*
X157455Y764419D01*
X157302Y764058D01*
X157110Y763748D01*
X156880Y763541D01*
X156573Y763386D01*
X155807D01*
G01X159022Y765969D02*
X159252Y766279D01*
X159520Y766434D01*
X159827Y766486D01*
X160210Y766383D01*
X160478Y766124D01*
X160555Y765814D01*
X160517Y765504D01*
X160363Y765246D01*
X159597Y764729D01*
X159252Y764368D01*
X159022Y763851D01*
X158945Y763386D01*
X160555D01*
G01X162773D02*
X162850Y764058D01*
X162965Y764626D01*
X163118Y765143D01*
X163310Y765711D01*
X163617Y766486D01*
X162083D01*
G01X165950Y763386D02*
Y766486D01*
X165490Y765866D01*
G01Y763386D02*
X166410D01*
G01X149927Y767600D02*
X149827Y764900D01*
Y768000D01*
G01X150600Y784100D02*
Y777900D01*
X147400D01*
Y784100D01*
X150600D01*
G01X153413Y801500D02*
X150987D01*
G01X151807Y796000D02*
Y799100D01*
X152573D01*
X152880Y798945D01*
X153110Y798738D01*
X153302Y798428D01*
X153455Y798067D01*
X153493Y797550D01*
X153455Y797033D01*
X153302Y796672D01*
X153110Y796362D01*
X152880Y796155D01*
X152573Y796000D01*
X151807D01*
G01X155022Y798583D02*
X155252Y798893D01*
X155520Y799048D01*
X155827Y799100D01*
X156210Y798997D01*
X156478Y798738D01*
X156555Y798428D01*
X156517Y798118D01*
X156363Y797860D01*
X155597Y797343D01*
X155252Y796982D01*
X155022Y796465D01*
X154945Y796000D01*
X156555D01*
G01X158122Y797292D02*
X158390Y797653D01*
X158620Y797860D01*
X158927Y797963D01*
X159195Y797860D01*
X159387Y797653D01*
X159540Y797343D01*
X159578Y796982D01*
X159540Y796672D01*
X159387Y796362D01*
X159157Y796103D01*
X158888Y796000D01*
X158582Y796103D01*
X158313Y796413D01*
X158160Y796878D01*
X158122Y797395D01*
X158198Y798067D01*
X158313Y798428D01*
X158505Y798790D01*
X158773Y799048D01*
X159042Y799100D01*
X159310Y798997D01*
X159502Y798738D01*
G01X161298Y796362D02*
X161567Y796103D01*
X161873Y796000D01*
X162180Y796103D01*
X162448Y796413D01*
X162640Y796878D01*
X162717Y797343D01*
Y797912D01*
X162640Y798377D01*
X162448Y798790D01*
X162218Y798997D01*
X161950Y799100D01*
X161643Y798997D01*
X161413Y798790D01*
X161260Y798480D01*
X161183Y798067D01*
X161260Y797705D01*
X161452Y797343D01*
X161682Y797137D01*
X161950Y797085D01*
X162257Y797188D01*
X162487Y797447D01*
X162717Y797912D01*
G01X149927Y802600D02*
X149827Y799900D01*
Y803000D01*
G01X153913Y791500D02*
X151487D01*
G01X154807Y790000D02*
Y793100D01*
X155573D01*
X155880Y792945D01*
X156110Y792738D01*
X156302Y792428D01*
X156455Y792067D01*
X156493Y791550D01*
X156455Y791033D01*
X156302Y790672D01*
X156110Y790362D01*
X155880Y790155D01*
X155573Y790000D01*
X154807D01*
G01X158022Y792583D02*
X158252Y792893D01*
X158520Y793048D01*
X158827Y793100D01*
X159210Y792997D01*
X159478Y792738D01*
X159555Y792428D01*
X159517Y792118D01*
X159363Y791860D01*
X158597Y791343D01*
X158252Y790982D01*
X158022Y790465D01*
X157945Y790000D01*
X159555D01*
G01X161773D02*
X161850Y790672D01*
X161965Y791240D01*
X162118Y791757D01*
X162310Y792325D01*
X162617Y793100D01*
X161083D01*
G01X164950D02*
X164643Y792997D01*
X164413Y792738D01*
X164260Y792428D01*
X164145Y792015D01*
X164107Y791550D01*
X164145Y791085D01*
X164260Y790672D01*
X164413Y790362D01*
X164643Y790103D01*
X164950Y790000D01*
X165257Y790103D01*
X165487Y790362D01*
X165640Y790672D01*
X165755Y791085D01*
X165793Y791550D01*
X165755Y792015D01*
X165640Y792428D01*
X165487Y792738D01*
X165257Y792997D01*
X164950Y793100D01*
G01X150427Y792600D02*
X150327Y789900D01*
Y793000D01*
G01X150500Y829314D02*
Y823914D01*
G01X150000D02*
Y829314D01*
G01X149500D02*
Y823914D01*
G01X154307Y821500D02*
Y824600D01*
X155073D01*
X155380Y824445D01*
X155610Y824238D01*
X155802Y823928D01*
X155955Y823567D01*
X155993Y823050D01*
X155955Y822533D01*
X155802Y822172D01*
X155610Y821862D01*
X155380Y821655D01*
X155073Y821500D01*
X154307D01*
G01X157522Y824083D02*
X157752Y824393D01*
X158020Y824548D01*
X158327Y824600D01*
X158710Y824497D01*
X158978Y824238D01*
X159055Y823928D01*
X159017Y823618D01*
X158863Y823360D01*
X158097Y822843D01*
X157752Y822482D01*
X157522Y821965D01*
X157445Y821500D01*
X159055D01*
G01X161273D02*
X161350Y822172D01*
X161465Y822740D01*
X161618Y823257D01*
X161810Y823825D01*
X162117Y824600D01*
X160583D01*
G01X163722Y824083D02*
X163952Y824393D01*
X164220Y824548D01*
X164527Y824600D01*
X164910Y824497D01*
X165178Y824238D01*
X165255Y823928D01*
X165217Y823618D01*
X165063Y823360D01*
X164297Y822843D01*
X163952Y822482D01*
X163722Y821965D01*
X163645Y821500D01*
X165255D01*
G01X153807Y829000D02*
Y832100D01*
X154573D01*
X154880Y831945D01*
X155110Y831738D01*
X155302Y831428D01*
X155455Y831067D01*
X155493Y830550D01*
X155455Y830033D01*
X155302Y829672D01*
X155110Y829362D01*
X154880Y829155D01*
X154573Y829000D01*
X153807D01*
G01X157750D02*
Y832100D01*
X157290Y831480D01*
G01Y829000D02*
X158210D01*
G01X160007Y829620D02*
X160237Y829258D01*
X160543Y829052D01*
X160888Y829000D01*
X161195Y829052D01*
X161502Y829310D01*
X161693Y829620D01*
X161732Y829930D01*
X161655Y830292D01*
X161387Y830550D01*
X161118Y830653D01*
X160773D01*
G01X161118D02*
X161348Y830808D01*
X161540Y831067D01*
X161617Y831377D01*
X161540Y831687D01*
X161348Y831945D01*
X161003Y832100D01*
X160658Y832048D01*
X160313Y831842D01*
G01X163107Y829620D02*
X163337Y829258D01*
X163643Y829052D01*
X163988Y829000D01*
X164295Y829052D01*
X164602Y829310D01*
X164793Y829620D01*
X164832Y829930D01*
X164755Y830292D01*
X164487Y830550D01*
X164218Y830653D01*
X163873D01*
G01X164218D02*
X164448Y830808D01*
X164640Y831067D01*
X164717Y831377D01*
X164640Y831687D01*
X164448Y831945D01*
X164103Y832100D01*
X163758Y832048D01*
X163413Y831842D01*
G01X163617Y849690D02*
Y847468D01*
X163770Y847003D01*
X164077Y846693D01*
X164460Y846590D01*
X164843Y846693D01*
X165150Y847003D01*
X165303Y847468D01*
Y849690D01*
G01X168020Y846590D02*
Y849690D01*
X166602Y847468D01*
X168518D01*
G01X170660Y849690D02*
X170353Y849587D01*
X170123Y849328D01*
X169970Y849018D01*
X169855Y848605D01*
X169817Y848140D01*
X169855Y847675D01*
X169970Y847262D01*
X170123Y846952D01*
X170353Y846693D01*
X170660Y846590D01*
X170967Y846693D01*
X171197Y846952D01*
X171350Y847262D01*
X171465Y847675D01*
X171503Y848140D01*
X171465Y848605D01*
X171350Y849018D01*
X171197Y849328D01*
X170967Y849587D01*
X170660Y849690D01*
G01X173032Y847882D02*
X173300Y848243D01*
X173530Y848450D01*
X173837Y848553D01*
X174105Y848450D01*
X174297Y848243D01*
X174450Y847933D01*
X174488Y847572D01*
X174450Y847262D01*
X174297Y846952D01*
X174067Y846693D01*
X173798Y846590D01*
X173492Y846693D01*
X173223Y847003D01*
X173070Y847468D01*
X173032Y847985D01*
X173108Y848657D01*
X173223Y849018D01*
X173415Y849380D01*
X173683Y849638D01*
X173952Y849690D01*
X174220Y849587D01*
X174412Y849328D01*
G01X164743Y860331D02*
Y851669D01*
X175257D01*
Y860331D01*
X164743D01*
G01X162600Y859100D02*
Y852900D01*
X159400D01*
Y859100D01*
X162600D01*
G01X154882Y1000249D02*
X161082D01*
Y997049D01*
X154882D01*
Y1000249D01*
G01X157458Y1002900D02*
X151258D01*
Y1006100D01*
X157458D01*
Y1002900D01*
G01X164758Y1012100D02*
X170958D01*
Y1008900D01*
X164758D01*
Y1012100D01*
G01X161082Y992049D02*
X154882D01*
Y995249D01*
X161082D01*
Y992049D01*
G01X151258Y1011100D02*
X157458D01*
Y1007900D01*
X151258D01*
Y1011100D01*
G01X163400Y1023100D02*
X169600D01*
Y1019900D01*
X163400D01*
Y1023100D01*
G01X169600Y1023900D02*
X163400D01*
Y1027100D01*
X169600D01*
Y1023900D01*
G01Y1015900D02*
X163400D01*
Y1019100D01*
X169600D01*
Y1015900D01*
G01X170400D02*
Y1022100D01*
X173600D01*
Y1015900D01*
X170400D01*
G01X150383Y1060000D02*
Y1063100D01*
X151303D01*
X151610Y1062945D01*
X151840Y1062583D01*
X151917Y1062170D01*
X151840Y1061757D01*
X151648Y1061447D01*
X151303Y1061292D01*
X150383D01*
G01X155093Y1062842D02*
X154863Y1062997D01*
X154595Y1063100D01*
X154288D01*
X153943Y1062945D01*
X153675Y1062687D01*
X153483Y1062377D01*
X153330Y1061860D01*
X153292Y1061395D01*
X153368Y1060930D01*
X153483Y1060620D01*
X153713Y1060310D01*
X153982Y1060103D01*
X154250Y1060000D01*
X154518D01*
X154787Y1060103D01*
X155017Y1060258D01*
X155208Y1060465D01*
G01X157273Y1060000D02*
X157350Y1060672D01*
X157465Y1061240D01*
X157618Y1061757D01*
X157810Y1062325D01*
X158117Y1063100D01*
X156583D01*
G01X158169Y1089972D02*
Y1100741D01*
X153169Y1105741D01*
G01X152307Y1125000D02*
Y1128100D01*
X153073D01*
X153380Y1127945D01*
X153610Y1127738D01*
X153802Y1127428D01*
X153955Y1127067D01*
X153993Y1126550D01*
X153955Y1126033D01*
X153802Y1125672D01*
X153610Y1125362D01*
X153380Y1125155D01*
X153073Y1125000D01*
X152307D01*
G01X155522Y1127583D02*
X155752Y1127893D01*
X156020Y1128048D01*
X156327Y1128100D01*
X156710Y1127997D01*
X156978Y1127738D01*
X157055Y1127428D01*
X157017Y1127118D01*
X156863Y1126860D01*
X156097Y1126343D01*
X155752Y1125982D01*
X155522Y1125465D01*
X155445Y1125000D01*
X157055D01*
G01X158622Y1126292D02*
X158890Y1126653D01*
X159120Y1126860D01*
X159427Y1126963D01*
X159695Y1126860D01*
X159887Y1126653D01*
X160040Y1126343D01*
X160078Y1125982D01*
X160040Y1125672D01*
X159887Y1125362D01*
X159657Y1125103D01*
X159388Y1125000D01*
X159082Y1125103D01*
X158813Y1125413D01*
X158660Y1125878D01*
X158622Y1126395D01*
X158698Y1127067D01*
X158813Y1127428D01*
X159005Y1127790D01*
X159273Y1128048D01*
X159542Y1128100D01*
X159810Y1127997D01*
X160002Y1127738D01*
G01X161607Y1125465D02*
X161837Y1125207D01*
X162105Y1125052D01*
X162450Y1125000D01*
X162795Y1125103D01*
X163063Y1125310D01*
X163255Y1125672D01*
X163293Y1126085D01*
X163217Y1126498D01*
X163025Y1126757D01*
X162757Y1126963D01*
X162488Y1127015D01*
X162220Y1126963D01*
X161875Y1126757D01*
X161990Y1128100D01*
X163025D01*
G01X152307Y1129500D02*
Y1132600D01*
X153073D01*
X153380Y1132445D01*
X153610Y1132238D01*
X153802Y1131928D01*
X153955Y1131567D01*
X153993Y1131050D01*
X153955Y1130533D01*
X153802Y1130172D01*
X153610Y1129862D01*
X153380Y1129655D01*
X153073Y1129500D01*
X152307D01*
G01X156250D02*
Y1132600D01*
X155790Y1131980D01*
G01Y1129500D02*
X156710D01*
G01X158507Y1130120D02*
X158737Y1129758D01*
X159043Y1129552D01*
X159388Y1129500D01*
X159695Y1129552D01*
X160002Y1129810D01*
X160193Y1130120D01*
X160232Y1130430D01*
X160155Y1130792D01*
X159887Y1131050D01*
X159618Y1131153D01*
X159273D01*
G01X159618D02*
X159848Y1131308D01*
X160040Y1131567D01*
X160117Y1131877D01*
X160040Y1132187D01*
X159848Y1132445D01*
X159503Y1132600D01*
X159158Y1132548D01*
X158813Y1132342D01*
G01X161722Y1132083D02*
X161952Y1132393D01*
X162220Y1132548D01*
X162527Y1132600D01*
X162910Y1132497D01*
X163178Y1132238D01*
X163255Y1131928D01*
X163217Y1131618D01*
X163063Y1131360D01*
X162297Y1130843D01*
X161952Y1130482D01*
X161722Y1129965D01*
X161645Y1129500D01*
X163255D01*
G01X150000Y1132300D02*
Y1137700D01*
G01X149500D02*
Y1132300D01*
G01X153913Y1151000D02*
X151487D01*
G01X154807Y1149500D02*
Y1152600D01*
X155573D01*
X155880Y1152445D01*
X156110Y1152238D01*
X156302Y1151928D01*
X156455Y1151567D01*
X156493Y1151050D01*
X156455Y1150533D01*
X156302Y1150172D01*
X156110Y1149862D01*
X155880Y1149655D01*
X155573Y1149500D01*
X154807D01*
G01X158022Y1152083D02*
X158252Y1152393D01*
X158520Y1152548D01*
X158827Y1152600D01*
X159210Y1152497D01*
X159478Y1152238D01*
X159555Y1151928D01*
X159517Y1151618D01*
X159363Y1151360D01*
X158597Y1150843D01*
X158252Y1150482D01*
X158022Y1149965D01*
X157945Y1149500D01*
X159555D01*
G01X161122Y1150792D02*
X161390Y1151153D01*
X161620Y1151360D01*
X161927Y1151463D01*
X162195Y1151360D01*
X162387Y1151153D01*
X162540Y1150843D01*
X162578Y1150482D01*
X162540Y1150172D01*
X162387Y1149862D01*
X162157Y1149603D01*
X161888Y1149500D01*
X161582Y1149603D01*
X161313Y1149913D01*
X161160Y1150378D01*
X161122Y1150895D01*
X161198Y1151567D01*
X161313Y1151928D01*
X161505Y1152290D01*
X161773Y1152548D01*
X162042Y1152600D01*
X162310Y1152497D01*
X162502Y1152238D01*
G01X164107Y1150120D02*
X164337Y1149758D01*
X164643Y1149552D01*
X164988Y1149500D01*
X165295Y1149552D01*
X165602Y1149810D01*
X165793Y1150120D01*
X165832Y1150430D01*
X165755Y1150792D01*
X165487Y1151050D01*
X165218Y1151153D01*
X164873D01*
G01X165218D02*
X165448Y1151308D01*
X165640Y1151567D01*
X165717Y1151877D01*
X165640Y1152187D01*
X165448Y1152445D01*
X165103Y1152600D01*
X164758Y1152548D01*
X164413Y1152342D01*
G01X153913Y1141500D02*
X151487D01*
G01X154807Y1140000D02*
Y1143100D01*
X155573D01*
X155880Y1142945D01*
X156110Y1142738D01*
X156302Y1142428D01*
X156455Y1142067D01*
X156493Y1141550D01*
X156455Y1141033D01*
X156302Y1140672D01*
X156110Y1140362D01*
X155880Y1140155D01*
X155573Y1140000D01*
X154807D01*
G01X158022Y1142583D02*
X158252Y1142893D01*
X158520Y1143048D01*
X158827Y1143100D01*
X159210Y1142997D01*
X159478Y1142738D01*
X159555Y1142428D01*
X159517Y1142118D01*
X159363Y1141860D01*
X158597Y1141343D01*
X158252Y1140982D01*
X158022Y1140465D01*
X157945Y1140000D01*
X159555D01*
G01X161122Y1141292D02*
X161390Y1141653D01*
X161620Y1141860D01*
X161927Y1141963D01*
X162195Y1141860D01*
X162387Y1141653D01*
X162540Y1141343D01*
X162578Y1140982D01*
X162540Y1140672D01*
X162387Y1140362D01*
X162157Y1140103D01*
X161888Y1140000D01*
X161582Y1140103D01*
X161313Y1140413D01*
X161160Y1140878D01*
X161122Y1141395D01*
X161198Y1142067D01*
X161313Y1142428D01*
X161505Y1142790D01*
X161773Y1143048D01*
X162042Y1143100D01*
X162310Y1142997D01*
X162502Y1142738D01*
G01X165410Y1140000D02*
Y1143100D01*
X163992Y1140878D01*
X165908D01*
G01X150427Y1142600D02*
X150327Y1139900D01*
Y1143000D01*
G01X150427Y1152100D02*
X150327Y1149400D01*
Y1152500D01*
G01X151987Y1192730D02*
Y1195830D01*
X152753D01*
X153060Y1195675D01*
X153290Y1195468D01*
X153482Y1195158D01*
X153635Y1194797D01*
X153673Y1194280D01*
X153635Y1193763D01*
X153482Y1193402D01*
X153290Y1193092D01*
X153060Y1192885D01*
X152753Y1192730D01*
X151987D01*
G01X155930D02*
Y1195830D01*
X155470Y1195210D01*
G01Y1192730D02*
X156390D01*
G01X158187Y1193350D02*
X158417Y1192988D01*
X158723Y1192782D01*
X159068Y1192730D01*
X159375Y1192782D01*
X159682Y1193040D01*
X159873Y1193350D01*
X159912Y1193660D01*
X159835Y1194022D01*
X159567Y1194280D01*
X159298Y1194383D01*
X158953D01*
G01X159298D02*
X159528Y1194538D01*
X159720Y1194797D01*
X159797Y1195107D01*
X159720Y1195417D01*
X159528Y1195675D01*
X159183Y1195830D01*
X158838Y1195778D01*
X158493Y1195572D01*
G01X162130Y1192730D02*
Y1195830D01*
X161670Y1195210D01*
G01Y1192730D02*
X162590D01*
G01X150000Y1187300D02*
Y1192700D01*
G01X149500D02*
Y1187300D01*
G01X153913Y1183500D02*
X151487D01*
G01X153807Y1185000D02*
Y1188100D01*
X154573D01*
X154880Y1187945D01*
X155110Y1187738D01*
X155302Y1187428D01*
X155455Y1187067D01*
X155493Y1186550D01*
X155455Y1186033D01*
X155302Y1185672D01*
X155110Y1185362D01*
X154880Y1185155D01*
X154573Y1185000D01*
X153807D01*
G01X157022Y1187583D02*
X157252Y1187893D01*
X157520Y1188048D01*
X157827Y1188100D01*
X158210Y1187997D01*
X158478Y1187738D01*
X158555Y1187428D01*
X158517Y1187118D01*
X158363Y1186860D01*
X157597Y1186343D01*
X157252Y1185982D01*
X157022Y1185465D01*
X156945Y1185000D01*
X158555D01*
G01X160122Y1186292D02*
X160390Y1186653D01*
X160620Y1186860D01*
X160927Y1186963D01*
X161195Y1186860D01*
X161387Y1186653D01*
X161540Y1186343D01*
X161578Y1185982D01*
X161540Y1185672D01*
X161387Y1185362D01*
X161157Y1185103D01*
X160888Y1185000D01*
X160582Y1185103D01*
X160313Y1185413D01*
X160160Y1185878D01*
X160122Y1186395D01*
X160198Y1187067D01*
X160313Y1187428D01*
X160505Y1187790D01*
X160773Y1188048D01*
X161042Y1188100D01*
X161310Y1187997D01*
X161502Y1187738D01*
G01X163222Y1186292D02*
X163490Y1186653D01*
X163720Y1186860D01*
X164027Y1186963D01*
X164295Y1186860D01*
X164487Y1186653D01*
X164640Y1186343D01*
X164678Y1185982D01*
X164640Y1185672D01*
X164487Y1185362D01*
X164257Y1185103D01*
X163988Y1185000D01*
X163682Y1185103D01*
X163413Y1185413D01*
X163260Y1185878D01*
X163222Y1186395D01*
X163298Y1187067D01*
X163413Y1187428D01*
X163605Y1187790D01*
X163873Y1188048D01*
X164142Y1188100D01*
X164410Y1187997D01*
X164602Y1187738D01*
G01X150427Y1184600D02*
X150327Y1181900D01*
Y1185000D01*
G01X171050Y1213180D02*
X170743Y1213232D01*
X170475Y1213438D01*
X170245Y1213748D01*
X170092Y1214110D01*
X170015Y1214523D01*
Y1214937D01*
X170092Y1215350D01*
X170245Y1215712D01*
X170475Y1216022D01*
X170743Y1216228D01*
X171050Y1216280D01*
X171357Y1216228D01*
X171625Y1216022D01*
X171855Y1215712D01*
X172008Y1215350D01*
X172085Y1214937D01*
Y1214523D01*
X172008Y1214110D01*
X171855Y1213748D01*
X171625Y1213438D01*
X171357Y1213232D01*
X171050Y1213180D01*
G01X171357Y1214007D02*
X171817Y1213180D01*
G01X173498Y1213542D02*
X173767Y1213283D01*
X174073Y1213180D01*
X174380Y1213283D01*
X174648Y1213593D01*
X174840Y1214058D01*
X174917Y1214523D01*
Y1215092D01*
X174840Y1215557D01*
X174648Y1215970D01*
X174418Y1216177D01*
X174150Y1216280D01*
X173843Y1216177D01*
X173613Y1215970D01*
X173460Y1215660D01*
X173383Y1215247D01*
X173460Y1214885D01*
X173652Y1214523D01*
X173882Y1214317D01*
X174150Y1214265D01*
X174457Y1214368D01*
X174687Y1214627D01*
X174917Y1215092D01*
G01X179500Y1218000D02*
X166500D01*
Y1233000D01*
X179500D01*
Y1218000D01*
G01X154699Y1213500D02*
Y1207500D01*
X148699D01*
G01Y1231122D02*
X154699D01*
Y1225122D01*
G01X174345Y29000D02*
Y32100D01*
G01X175955D02*
Y29000D01*
G01Y30550D02*
X174345D01*
G01X178250Y29000D02*
Y32100D01*
X177790Y31480D01*
G01Y29000D02*
X178710D01*
G01X181810D02*
Y32100D01*
X180392Y29878D01*
X182308D01*
G01X172883Y130000D02*
Y133100D01*
X173803D01*
X174110Y132945D01*
X174340Y132583D01*
X174417Y132170D01*
X174340Y131757D01*
X174148Y131447D01*
X173803Y131292D01*
X172883D01*
G01X177593Y132842D02*
X177363Y132997D01*
X177095Y133100D01*
X176788D01*
X176443Y132945D01*
X176175Y132687D01*
X175983Y132377D01*
X175830Y131860D01*
X175792Y131395D01*
X175868Y130930D01*
X175983Y130620D01*
X176213Y130310D01*
X176482Y130103D01*
X176750Y130000D01*
X177018D01*
X177287Y130103D01*
X177517Y130258D01*
X177708Y130465D01*
G01X179007Y130620D02*
X179237Y130258D01*
X179543Y130052D01*
X179888Y130000D01*
X180195Y130052D01*
X180502Y130310D01*
X180693Y130620D01*
X180732Y130930D01*
X180655Y131292D01*
X180387Y131550D01*
X180118Y131653D01*
X179773D01*
G01X180118D02*
X180348Y131808D01*
X180540Y132067D01*
X180617Y132377D01*
X180540Y132687D01*
X180348Y132945D01*
X180003Y133100D01*
X179658Y133048D01*
X179313Y132842D01*
G01X182107Y130465D02*
X182337Y130207D01*
X182605Y130052D01*
X182950Y130000D01*
X183295Y130103D01*
X183563Y130310D01*
X183755Y130672D01*
X183793Y131085D01*
X183717Y131498D01*
X183525Y131757D01*
X183257Y131963D01*
X182988Y132015D01*
X182720Y131963D01*
X182375Y131757D01*
X182490Y133100D01*
X183525D01*
G01X195100Y122900D02*
X188900D01*
Y126100D01*
X195100D01*
Y122900D01*
G01X182600D02*
X176400D01*
Y126100D01*
X182600D01*
Y122900D01*
G01X186054Y148131D02*
X192054D01*
Y136131D01*
X186054D01*
Y148131D01*
G01X196454Y146031D02*
Y139831D01*
X193254D01*
Y146031D01*
X196454D01*
G01X177458Y283828D02*
Y277628D01*
X174258D01*
Y283828D01*
X177458D01*
G01X177400Y385900D02*
Y392100D01*
X180600D01*
Y385900D01*
X177400D01*
G01X198000Y394500D02*
Y381500D01*
X183000D01*
Y394500D01*
X198000D01*
G01X192310Y396170D02*
X192003Y396222D01*
X191735Y396428D01*
X191505Y396738D01*
X191352Y397100D01*
X191275Y397513D01*
Y397927D01*
X191352Y398340D01*
X191505Y398702D01*
X191735Y399012D01*
X192003Y399218D01*
X192310Y399270D01*
X192617Y399218D01*
X192885Y399012D01*
X193115Y398702D01*
X193268Y398340D01*
X193345Y397927D01*
Y397513D01*
X193268Y397100D01*
X193115Y396738D01*
X192885Y396428D01*
X192617Y396222D01*
X192310Y396170D01*
G01X192617Y396997D02*
X193077Y396170D01*
G01X195410D02*
Y399270D01*
X194950Y398650D01*
G01Y396170D02*
X195870D01*
G01X198510D02*
Y399270D01*
X198050Y398650D01*
G01Y396170D02*
X198970D01*
G01X194000Y499000D02*
Y493000D01*
X182000D01*
Y499000D01*
X194000D01*
G01X179900Y485400D02*
Y491600D01*
X183100D01*
Y485400D01*
X179900D01*
G01X179100Y491600D02*
Y485400D01*
X175900D01*
Y491600D01*
X179100D01*
G01X191600Y488400D02*
X185400D01*
Y491600D01*
X191600D01*
Y488400D01*
G01X193100Y513900D02*
X186900D01*
Y517100D01*
X193100D01*
Y513900D01*
G01Y519400D02*
X186900D01*
Y522600D01*
X193100D01*
Y519400D01*
G01Y524900D02*
X186900D01*
Y528100D01*
X193100D01*
Y524900D01*
G01X183290Y526790D02*
X185790D01*
X185290Y527110D01*
G01X183290D02*
Y526470D01*
G01Y524590D02*
X183332Y524403D01*
X183457Y524190D01*
X183665Y524057D01*
X183957Y524003D01*
X184248Y524057D01*
X184498Y524217D01*
X184623Y524457D01*
Y524723D01*
X184707Y524883D01*
X184915Y525017D01*
X185207Y525070D01*
X185498Y524990D01*
X185707Y524803D01*
X185790Y524590D01*
X185707Y524377D01*
X185498Y524190D01*
X185207Y524110D01*
X184915Y524163D01*
X184707Y524297D01*
X184623Y524457D01*
Y524723D01*
X184498Y524963D01*
X184248Y525123D01*
X183957Y525177D01*
X183665Y525123D01*
X183457Y524990D01*
X183332Y524777D01*
X183290Y524590D01*
G01X183750Y513100D02*
X186250D01*
X185750Y513420D01*
G01X183750D02*
Y512780D01*
G01X184250Y511487D02*
X183958Y511327D01*
X183792Y511113D01*
X183750Y510873D01*
X183792Y510660D01*
X184000Y510447D01*
X184250Y510313D01*
X184500Y510287D01*
X184792Y510340D01*
X185000Y510527D01*
X185083Y510713D01*
Y510953D01*
G01Y510713D02*
X185208Y510553D01*
X185417Y510420D01*
X185667Y510367D01*
X185917Y510420D01*
X186125Y510553D01*
X186250Y510793D01*
X186208Y511033D01*
X186042Y511273D01*
G01X178100Y504950D02*
Y507450D01*
X177780Y506950D01*
G01Y504950D02*
X178420D01*
G01X179793Y507033D02*
X179953Y507283D01*
X180140Y507408D01*
X180353Y507450D01*
X180620Y507367D01*
X180807Y507158D01*
X180860Y506908D01*
X180833Y506658D01*
X180727Y506450D01*
X180193Y506033D01*
X179953Y505742D01*
X179793Y505325D01*
X179740Y504950D01*
X180860D01*
G01X184307Y507600D02*
Y505378D01*
X184460Y504913D01*
X184767Y504603D01*
X185150Y504500D01*
X185533Y504603D01*
X185840Y504913D01*
X185993Y505378D01*
Y507600D01*
G01X188710Y504500D02*
Y507600D01*
X187292Y505378D01*
X189208D01*
G01X191350Y507600D02*
X191043Y507497D01*
X190813Y507238D01*
X190660Y506928D01*
X190545Y506515D01*
X190507Y506050D01*
X190545Y505585D01*
X190660Y505172D01*
X190813Y504862D01*
X191043Y504603D01*
X191350Y504500D01*
X191657Y504603D01*
X191887Y504862D01*
X192040Y505172D01*
X192155Y505585D01*
X192193Y506050D01*
X192155Y506515D01*
X192040Y506928D01*
X191887Y507238D01*
X191657Y507497D01*
X191350Y507600D01*
G01X193607Y505120D02*
X193837Y504758D01*
X194143Y504552D01*
X194488Y504500D01*
X194795Y504552D01*
X195102Y504810D01*
X195293Y505120D01*
X195332Y505430D01*
X195255Y505792D01*
X194987Y506050D01*
X194718Y506153D01*
X194373D01*
G01X194718D02*
X194948Y506308D01*
X195140Y506567D01*
X195217Y506877D01*
X195140Y507187D01*
X194948Y507445D01*
X194603Y507600D01*
X194258Y507548D01*
X193913Y507342D01*
G01X185400Y517000D02*
X183400D01*
G01X174000Y507600D02*
Y503600D01*
G01X180874Y512000D02*
Y510126D01*
X179000D01*
G01X180874Y525874D02*
Y524000D01*
G01X193100Y530400D02*
X186900D01*
Y533600D01*
X193100D01*
Y530400D01*
G01X178100Y536600D02*
Y530400D01*
X174900D01*
Y536600D01*
X178100D01*
G01X178900Y528500D02*
Y531000D01*
X178580Y530500D01*
G01Y528500D02*
X179220D01*
G01X180647Y528792D02*
X180833Y528583D01*
X181047Y528500D01*
X181260Y528583D01*
X181447Y528833D01*
X181580Y529208D01*
X181633Y529583D01*
Y530042D01*
X181580Y530417D01*
X181447Y530750D01*
X181287Y530917D01*
X181100Y531000D01*
X180887Y530917D01*
X180727Y530750D01*
X180620Y530500D01*
X180567Y530167D01*
X180620Y529875D01*
X180753Y529583D01*
X180913Y529417D01*
X181100Y529375D01*
X181313Y529458D01*
X181473Y529667D01*
X181633Y530042D01*
G01X179000Y525874D02*
X180874D01*
G01X176000Y529600D02*
Y528400D01*
G01X179400Y665100D02*
X185600D01*
Y661900D01*
X179400D01*
Y665100D01*
G01Y661100D02*
X185600D01*
Y657900D01*
X179400D01*
Y661100D01*
G01Y653600D02*
X185600D01*
Y650400D01*
X179400D01*
Y653600D01*
G01X174400Y707600D02*
X180600D01*
Y704400D01*
X174400D01*
Y707600D01*
G01X186400D02*
X192600D01*
Y704400D01*
X186400D01*
Y707600D01*
G01X174400Y734600D02*
X180600D01*
Y731400D01*
X174400D01*
Y734600D01*
G01X180600Y718400D02*
X174400D01*
Y721600D01*
X180600D01*
Y718400D01*
G01Y711400D02*
X174400D01*
Y714600D01*
X180600D01*
Y711400D01*
G01X182900Y734600D02*
X189100D01*
Y731400D01*
X182900D01*
Y734600D01*
G01X180600Y745400D02*
X174400D01*
Y748600D01*
X180600D01*
Y745400D01*
G01Y738400D02*
X174400D01*
Y741600D01*
X180600D01*
Y738400D01*
G01X188170Y844080D02*
X187863Y844132D01*
X187595Y844338D01*
X187365Y844648D01*
X187212Y845010D01*
X187135Y845423D01*
Y845837D01*
X187212Y846250D01*
X187365Y846612D01*
X187595Y846922D01*
X187863Y847128D01*
X188170Y847180D01*
X188477Y847128D01*
X188745Y846922D01*
X188975Y846612D01*
X189128Y846250D01*
X189205Y845837D01*
Y845423D01*
X189128Y845010D01*
X188975Y844648D01*
X188745Y844338D01*
X188477Y844132D01*
X188170Y844080D01*
G01X188477Y844907D02*
X188937Y844080D01*
G01X191270D02*
Y847180D01*
X190810Y846560D01*
G01Y844080D02*
X191730D01*
G01X194370Y847180D02*
X194063Y847077D01*
X193833Y846818D01*
X193680Y846508D01*
X193565Y846095D01*
X193527Y845630D01*
X193565Y845165D01*
X193680Y844752D01*
X193833Y844442D01*
X194063Y844183D01*
X194370Y844080D01*
X194677Y844183D01*
X194907Y844442D01*
X195060Y844752D01*
X195175Y845165D01*
X195213Y845630D01*
X195175Y846095D01*
X195060Y846508D01*
X194907Y846818D01*
X194677Y847077D01*
X194370Y847180D01*
G01X189000Y877000D02*
X195000D01*
Y865000D01*
X189000D01*
Y877000D01*
G01X177400Y852900D02*
Y859100D01*
X180600D01*
Y852900D01*
X177400D01*
G01X197500Y862500D02*
Y849500D01*
X182500D01*
Y862500D01*
X197500D01*
G01X182700Y865900D02*
Y876100D01*
X187300D01*
Y865900D01*
X182700D01*
G01X177458Y1010600D02*
Y1004400D01*
X174258D01*
Y1010600D01*
X177458D01*
G01X194000Y1224000D02*
Y1218000D01*
X182000D01*
Y1224000D01*
X194000D01*
G01X191100Y1213400D02*
X184900D01*
Y1216600D01*
X191100D01*
Y1213400D01*
G01X192331Y1237257D02*
X183669D01*
Y1226743D01*
X192331D01*
Y1237257D01*
G01X191100Y1238900D02*
X184900D01*
Y1242100D01*
X191100D01*
Y1238900D01*
G01X173400Y1238100D02*
X179600D01*
Y1234900D01*
X173400D01*
Y1238100D01*
G01X199100Y874100D02*
Y867900D01*
X195900D01*
Y874100D01*
X199100D01*
G01X194260Y1225837D02*
X196482D01*
X196947Y1225990D01*
X197257Y1226297D01*
X197360Y1226680D01*
X197257Y1227063D01*
X196947Y1227370D01*
X196482Y1227523D01*
X194260D01*
G01X197360Y1230240D02*
X194260D01*
X196482Y1228822D01*
Y1230738D01*
G01X194260Y1232880D02*
X194363Y1232573D01*
X194622Y1232343D01*
X194932Y1232190D01*
X195345Y1232075D01*
X195810Y1232037D01*
X196275Y1232075D01*
X196688Y1232190D01*
X196998Y1232343D01*
X197257Y1232573D01*
X197360Y1232880D01*
X197257Y1233187D01*
X196998Y1233417D01*
X196688Y1233570D01*
X196275Y1233685D01*
X195810Y1233723D01*
X195345Y1233685D01*
X194932Y1233570D01*
X194622Y1233417D01*
X194363Y1233187D01*
X194260Y1232880D01*
G01X196895Y1235137D02*
X197153Y1235367D01*
X197308Y1235635D01*
X197360Y1235980D01*
X197257Y1236325D01*
X197050Y1236593D01*
X196688Y1236785D01*
X196275Y1236823D01*
X195862Y1236747D01*
X195603Y1236555D01*
X195397Y1236287D01*
X195345Y1236018D01*
X195397Y1235750D01*
X195603Y1235405D01*
X194260Y1235520D01*
Y1236555D01*
G01X331395Y-304184D02*
X330925Y-303869D01*
X330377Y-303659D01*
X329750D01*
X329045Y-303974D01*
X328497Y-304499D01*
X328105Y-305129D01*
X327792Y-306179D01*
X327714Y-307124D01*
X327870Y-308069D01*
X328105Y-308699D01*
X328575Y-309329D01*
X329124Y-309749D01*
X329672Y-309959D01*
X330220D01*
X330769Y-309749D01*
X331239Y-309434D01*
X331630Y-309014D01*
G01X335032Y-303659D02*
X336912D01*
G01X335972D02*
Y-309959D01*
G01X335032D02*
X336912D01*
G01X342272Y-303659D02*
Y-309959D01*
G01X340470Y-303659D02*
X344074D01*
G01X348572Y-309959D02*
Y-307124D01*
X347005Y-303659D01*
G01X350139D02*
X348572Y-307124D01*
G01X359449Y-308699D02*
X359919Y-309434D01*
X360545Y-309854D01*
X361250Y-309959D01*
X361877Y-309854D01*
X362504Y-309329D01*
X362895Y-308699D01*
X362974Y-308069D01*
X362817Y-307334D01*
X362269Y-306809D01*
X361720Y-306599D01*
X361015D01*
G01X361720D02*
X362190Y-306284D01*
X362582Y-305759D01*
X362739Y-305129D01*
X362582Y-304499D01*
X362190Y-303974D01*
X361485Y-303659D01*
X360780Y-303764D01*
X360075Y-304184D01*
G01X365749Y-308699D02*
X366219Y-309434D01*
X366845Y-309854D01*
X367550Y-309959D01*
X368177Y-309854D01*
X368804Y-309329D01*
X369195Y-308699D01*
X369274Y-308069D01*
X369117Y-307334D01*
X368569Y-306809D01*
X368020Y-306599D01*
X367315D01*
G01X368020D02*
X368490Y-306284D01*
X368882Y-305759D01*
X369039Y-305129D01*
X368882Y-304499D01*
X368490Y-303974D01*
X367785Y-303659D01*
X367080Y-303764D01*
X366375Y-304184D01*
G01X372049Y-308699D02*
X372519Y-309434D01*
X373145Y-309854D01*
X373850Y-309959D01*
X374477Y-309854D01*
X375104Y-309329D01*
X375495Y-308699D01*
X375574Y-308069D01*
X375417Y-307334D01*
X374869Y-306809D01*
X374320Y-306599D01*
X373615D01*
G01X374320D02*
X374790Y-306284D01*
X375182Y-305759D01*
X375339Y-305129D01*
X375182Y-304499D01*
X374790Y-303974D01*
X374085Y-303659D01*
X373380Y-303764D01*
X372675Y-304184D01*
G01X379915Y-309959D02*
X380072Y-308594D01*
X380307Y-307439D01*
X380620Y-306389D01*
X381012Y-305234D01*
X381639Y-303659D01*
X378505D01*
G01X386215Y-309959D02*
X386372Y-308594D01*
X386607Y-307439D01*
X386920Y-306389D01*
X387312Y-305234D01*
X387939Y-303659D01*
X384805D01*
G01X392515Y-311114D02*
X392829Y-309749D01*
G01X398972Y-303659D02*
Y-309959D01*
G01X397170Y-303659D02*
X400774D01*
G01X403314Y-309959D02*
X405272Y-303659D01*
X407230Y-309959D01*
G01X406525Y-307754D02*
X404019D01*
G01X410632Y-303659D02*
X412512D01*
G01X411572D02*
Y-309959D01*
G01X410632D02*
X412512D01*
G01X415522Y-303659D02*
X416619Y-309959D01*
X417872Y-303659D01*
X419125Y-309959D01*
X420222Y-303659D01*
G01X422214Y-309959D02*
X424172Y-303659D01*
X426130Y-309959D01*
G01X425425Y-307754D02*
X422919D01*
G01X428670Y-309959D02*
Y-303659D01*
X432274Y-309959D01*
Y-303659D01*
G01X442680Y-312059D02*
X441897Y-311009D01*
X441505Y-309959D01*
Y-305759D01*
X441897Y-304709D01*
X442680Y-303659D01*
G01X454105Y-309959D02*
Y-303659D01*
X456064D01*
X456690Y-303974D01*
X457082Y-304394D01*
X457239Y-305234D01*
X457082Y-306074D01*
X456612Y-306599D01*
X456064Y-306914D01*
X454105D01*
G01X456064D02*
X457239Y-309959D01*
G01X461972Y-310169D02*
X461815Y-310064D01*
Y-309854D01*
X461972Y-309749D01*
X462129Y-309854D01*
Y-310064D01*
X461972Y-310169D01*
G01X468272Y-309959D02*
X467645Y-309854D01*
X467097Y-309434D01*
X466627Y-308804D01*
X466314Y-308069D01*
X466157Y-307229D01*
Y-306389D01*
X466314Y-305549D01*
X466627Y-304814D01*
X467097Y-304184D01*
X467645Y-303764D01*
X468272Y-303659D01*
X468899Y-303764D01*
X469447Y-304184D01*
X469917Y-304814D01*
X470230Y-305549D01*
X470387Y-306389D01*
Y-307229D01*
X470230Y-308069D01*
X469917Y-308804D01*
X469447Y-309434D01*
X468899Y-309854D01*
X468272Y-309959D01*
G01X474572Y-310169D02*
X474415Y-310064D01*
Y-309854D01*
X474572Y-309749D01*
X474729Y-309854D01*
Y-310064D01*
X474572Y-310169D01*
G01X482595Y-304184D02*
X482125Y-303869D01*
X481577Y-303659D01*
X480950D01*
X480245Y-303974D01*
X479697Y-304499D01*
X479305Y-305129D01*
X478992Y-306179D01*
X478914Y-307124D01*
X479070Y-308069D01*
X479305Y-308699D01*
X479775Y-309329D01*
X480324Y-309749D01*
X480872Y-309959D01*
X481420D01*
X481969Y-309749D01*
X482439Y-309434D01*
X482830Y-309014D01*
G01X487172Y-310169D02*
X487015Y-310064D01*
Y-309854D01*
X487172Y-309749D01*
X487329Y-309854D01*
Y-310064D01*
X487172Y-310169D01*
G01X493864Y-312059D02*
X494647Y-311009D01*
X495039Y-309959D01*
Y-305759D01*
X494647Y-304709D01*
X493864Y-303659D01*
G01X330142Y-296809D02*
X331709D01*
Y-298699D01*
X331239Y-299329D01*
X330690Y-299749D01*
X329907Y-299959D01*
X329124Y-299749D01*
X328575Y-299329D01*
X328105Y-298699D01*
X327792Y-297964D01*
X327635Y-297124D01*
Y-296389D01*
X327792Y-295759D01*
X328105Y-295024D01*
X328575Y-294394D01*
X329045Y-293974D01*
X329672Y-293659D01*
X330220D01*
X330847Y-293869D01*
X331317Y-294289D01*
G01X334249Y-293659D02*
Y-298174D01*
X334562Y-299119D01*
X335189Y-299749D01*
X335972Y-299959D01*
X336755Y-299749D01*
X337382Y-299119D01*
X337695Y-298174D01*
Y-293659D01*
G01X341332D02*
X343212D01*
G01X342272D02*
Y-299959D01*
G01X341332D02*
X343212D01*
G01X346927Y-299119D02*
X347554Y-299644D01*
X348259Y-299959D01*
X348885D01*
X349512Y-299644D01*
X349982Y-299119D01*
X350217Y-298384D01*
X350060Y-297649D01*
X349669Y-297019D01*
X348964Y-296599D01*
X348024Y-296389D01*
X347475Y-295969D01*
X347240Y-295234D01*
X347397Y-294499D01*
X347789Y-293974D01*
X348337Y-293659D01*
X348885D01*
X349434Y-293869D01*
X349904Y-294394D01*
G01X353227Y-299959D02*
Y-293659D01*
G01X356517D02*
Y-299959D01*
G01Y-296809D02*
X353227D01*
G01X359214Y-299959D02*
X361172Y-293659D01*
X363130Y-299959D01*
G01X362425Y-297754D02*
X359919D01*
G01X365670Y-299959D02*
Y-293659D01*
X369274Y-299959D01*
Y-293659D01*
G01X378349Y-299959D02*
Y-293659D01*
X379915D01*
X380542Y-293974D01*
X381012Y-294394D01*
X381404Y-295024D01*
X381717Y-295759D01*
X381795Y-296809D01*
X381717Y-297859D01*
X381404Y-298594D01*
X381012Y-299224D01*
X380542Y-299644D01*
X379915Y-299959D01*
X378349D01*
G01X385432Y-293659D02*
X387312D01*
G01X386372D02*
Y-299959D01*
G01X385432D02*
X387312D01*
G01X391027Y-299119D02*
X391654Y-299644D01*
X392359Y-299959D01*
X392985D01*
X393612Y-299644D01*
X394082Y-299119D01*
X394317Y-298384D01*
X394160Y-297649D01*
X393769Y-297019D01*
X393064Y-296599D01*
X392124Y-296389D01*
X391575Y-295969D01*
X391340Y-295234D01*
X391497Y-294499D01*
X391889Y-293974D01*
X392437Y-293659D01*
X392985D01*
X393534Y-293869D01*
X394004Y-294394D01*
G01X398972Y-293659D02*
Y-299959D01*
G01X397170Y-293659D02*
X400774D01*
G01X405272Y-300169D02*
X405115Y-300064D01*
Y-299854D01*
X405272Y-299749D01*
X405429Y-299854D01*
Y-300064D01*
X405272Y-300169D01*
G01X411415Y-301114D02*
X411729Y-299749D01*
G01X417872Y-293659D02*
Y-299959D01*
G01X416070Y-293659D02*
X419674D01*
G01X422214Y-299959D02*
X424172Y-293659D01*
X426130Y-299959D01*
G01X425425Y-297754D02*
X422919D01*
G01X430472Y-299959D02*
X429845Y-299854D01*
X429297Y-299434D01*
X428827Y-298804D01*
X428514Y-298069D01*
X428357Y-297229D01*
Y-296389D01*
X428514Y-295549D01*
X428827Y-294814D01*
X429297Y-294184D01*
X429845Y-293764D01*
X430472Y-293659D01*
X431099Y-293764D01*
X431647Y-294184D01*
X432117Y-294814D01*
X432430Y-295549D01*
X432587Y-296389D01*
Y-297229D01*
X432430Y-298069D01*
X432117Y-298804D01*
X431647Y-299434D01*
X431099Y-299854D01*
X430472Y-299959D01*
G01X436772D02*
Y-297124D01*
X435205Y-293659D01*
G01X438339D02*
X436772Y-297124D01*
G01X441349Y-293659D02*
Y-298174D01*
X441662Y-299119D01*
X442289Y-299749D01*
X443072Y-299959D01*
X443855Y-299749D01*
X444482Y-299119D01*
X444795Y-298174D01*
Y-293659D01*
G01X447414Y-299959D02*
X449372Y-293659D01*
X451330Y-299959D01*
G01X450625Y-297754D02*
X448119D01*
G01X453870Y-299959D02*
Y-293659D01*
X457474Y-299959D01*
Y-293659D01*
G01X327870Y-289959D02*
Y-283659D01*
X331474Y-289959D01*
Y-283659D01*
G01X335972Y-289959D02*
X335345Y-289854D01*
X334797Y-289434D01*
X334327Y-288804D01*
X334014Y-288069D01*
X333857Y-287229D01*
Y-286389D01*
X334014Y-285549D01*
X334327Y-284814D01*
X334797Y-284184D01*
X335345Y-283764D01*
X335972Y-283659D01*
X336599Y-283764D01*
X337147Y-284184D01*
X337617Y-284814D01*
X337930Y-285549D01*
X338087Y-286389D01*
Y-287229D01*
X337930Y-288069D01*
X337617Y-288804D01*
X337147Y-289434D01*
X336599Y-289854D01*
X335972Y-289959D01*
G01X342272Y-290169D02*
X342115Y-290064D01*
Y-289854D01*
X342272Y-289749D01*
X342429Y-289854D01*
Y-290064D01*
X342272Y-290169D01*
G01X347084Y-284709D02*
X347554Y-284079D01*
X348102Y-283764D01*
X348729Y-283659D01*
X349512Y-283869D01*
X350060Y-284394D01*
X350217Y-285024D01*
X350139Y-285654D01*
X349825Y-286179D01*
X348259Y-287229D01*
X347554Y-287964D01*
X347084Y-289014D01*
X346927Y-289959D01*
X350217D01*
G01X354872D02*
Y-283659D01*
X353932Y-284919D01*
G01Y-289959D02*
X355812D01*
G01X361172D02*
Y-283659D01*
X360232Y-284919D01*
G01Y-289959D02*
X362112D01*
G01X367315Y-291114D02*
X367629Y-289749D01*
G01X371422Y-283659D02*
X372519Y-289959D01*
X373772Y-283659D01*
X375025Y-289959D01*
X376122Y-283659D01*
G01X381639Y-289959D02*
X378505D01*
Y-283659D01*
X381639D01*
G01X380385Y-286704D02*
X378505D01*
G01X384570Y-289959D02*
Y-283659D01*
X388174Y-289959D01*
Y-283659D01*
G01X391027Y-289959D02*
Y-283659D01*
G01X394317D02*
Y-289959D01*
G01Y-286809D02*
X391027D01*
G01X397249Y-283659D02*
Y-288174D01*
X397562Y-289119D01*
X398189Y-289749D01*
X398972Y-289959D01*
X399755Y-289749D01*
X400382Y-289119D01*
X400695Y-288174D01*
Y-283659D01*
G01X403314Y-289959D02*
X405272Y-283659D01*
X407230Y-289959D01*
G01X406525Y-287754D02*
X404019D01*
G01X416384Y-284709D02*
X416854Y-284079D01*
X417402Y-283764D01*
X418029Y-283659D01*
X418812Y-283869D01*
X419360Y-284394D01*
X419517Y-285024D01*
X419439Y-285654D01*
X419125Y-286179D01*
X417559Y-287229D01*
X416854Y-287964D01*
X416384Y-289014D01*
X416227Y-289959D01*
X419517D01*
G01X422370D02*
Y-283659D01*
X425974Y-289959D01*
Y-283659D01*
G01X428749Y-289959D02*
Y-283659D01*
X430315D01*
X430942Y-283974D01*
X431412Y-284394D01*
X431804Y-285024D01*
X432117Y-285759D01*
X432195Y-286809D01*
X432117Y-287859D01*
X431804Y-288594D01*
X431412Y-289224D01*
X430942Y-289644D01*
X430315Y-289959D01*
X428749D01*
G01X441505D02*
Y-283659D01*
X443464D01*
X444090Y-283974D01*
X444482Y-284394D01*
X444639Y-285234D01*
X444482Y-286074D01*
X444012Y-286599D01*
X443464Y-286914D01*
X441505D01*
G01X443464D02*
X444639Y-289959D01*
G01X447649D02*
Y-283659D01*
X449215D01*
X449842Y-283974D01*
X450312Y-284394D01*
X450704Y-285024D01*
X451017Y-285759D01*
X451095Y-286809D01*
X451017Y-287859D01*
X450704Y-288594D01*
X450312Y-289224D01*
X449842Y-289644D01*
X449215Y-289959D01*
X447649D01*
G01X455672Y-290169D02*
X455515Y-290064D01*
Y-289854D01*
X455672Y-289749D01*
X455829Y-289854D01*
Y-290064D01*
X455672Y-290169D01*
G01X351972Y-279259D02*
X349452Y-278842D01*
X347247Y-277176D01*
X345357Y-274676D01*
X344097Y-271759D01*
X343467Y-268426D01*
Y-265092D01*
X344097Y-261759D01*
X345357Y-258842D01*
X347247Y-256343D01*
X349452Y-254676D01*
X351972Y-254259D01*
X354492Y-254676D01*
X356697Y-256343D01*
X358587Y-258842D01*
X359847Y-261759D01*
X360477Y-265092D01*
Y-268426D01*
X359847Y-271759D01*
X358587Y-274676D01*
X356697Y-277176D01*
X354492Y-278842D01*
X351972Y-279259D01*
G01X354492Y-272592D02*
X358272Y-279259D01*
G01X371817Y-262593D02*
Y-274259D01*
X373077Y-277176D01*
X374967Y-278842D01*
X377172Y-279259D01*
X379377Y-278842D01*
X381267Y-277176D01*
X382527Y-274259D01*
G01Y-279259D02*
Y-262593D01*
G01X408042Y-279259D02*
Y-262593D01*
G01Y-265509D02*
X406782Y-263843D01*
X404892Y-263009D01*
X402687Y-262593D01*
X400482Y-263426D01*
X398592Y-265092D01*
X397332Y-267593D01*
X396702Y-270926D01*
X397332Y-274259D01*
X398592Y-276760D01*
X400482Y-278426D01*
X402687Y-279259D01*
X404892Y-278842D01*
X406782Y-277593D01*
X408042Y-275926D01*
G01X422217Y-279259D02*
Y-262593D01*
G01Y-266759D02*
X423477Y-264676D01*
X425367Y-263009D01*
X427887Y-262593D01*
X430092Y-263009D01*
X431982Y-264676D01*
X432927Y-267593D01*
Y-279259D01*
G01X452772Y-254259D02*
Y-279259D01*
G01X448362Y-262593D02*
X457182D01*
G01X483642Y-279259D02*
Y-262593D01*
G01Y-265509D02*
X482382Y-263843D01*
X480492Y-263009D01*
X478287Y-262593D01*
X476082Y-263426D01*
X474192Y-265092D01*
X472932Y-267593D01*
X472302Y-270926D01*
X472932Y-274259D01*
X474192Y-276760D01*
X476082Y-278426D01*
X478287Y-279259D01*
X480492Y-278842D01*
X482382Y-277593D01*
X483642Y-275926D01*
G01X534722Y-290893D02*
X535522Y-291559D01*
X536422Y-291959D01*
X537222D01*
X538022Y-291559D01*
X538622Y-290893D01*
X538922Y-289959D01*
X538722Y-289026D01*
X538222Y-288226D01*
X537322Y-287692D01*
X536122Y-287426D01*
X535422Y-286892D01*
X535122Y-285959D01*
X535322Y-285026D01*
X535822Y-284359D01*
X536522Y-283959D01*
X537222D01*
X537922Y-284226D01*
X538522Y-284892D01*
G01X543622Y-283959D02*
X546022D01*
G01X544822D02*
Y-291959D01*
G01X543622D02*
X546022D01*
G01X550822Y-283959D02*
Y-291959D01*
X554822D01*
G01X558622D02*
Y-283959D01*
G01X562422D02*
X558622Y-288893D01*
G01X563022Y-291959D02*
X560322Y-286626D01*
G01X567522Y-289292D02*
X570122D01*
G01X576822Y-283959D02*
Y-291959D01*
G01X574522Y-283959D02*
X579122D01*
G01X584822Y-291959D02*
X584022Y-291826D01*
X583322Y-291292D01*
X582722Y-290492D01*
X582322Y-289559D01*
X582122Y-288492D01*
Y-287426D01*
X582322Y-286359D01*
X582722Y-285426D01*
X583322Y-284626D01*
X584022Y-284092D01*
X584822Y-283959D01*
X585622Y-284092D01*
X586322Y-284626D01*
X586922Y-285426D01*
X587322Y-286359D01*
X587522Y-287426D01*
Y-288492D01*
X587322Y-289559D01*
X586922Y-290492D01*
X586322Y-291292D01*
X585622Y-291826D01*
X584822Y-291959D01*
G01X590822D02*
Y-283959D01*
X593222D01*
X594022Y-284359D01*
X594622Y-285292D01*
X594822Y-286359D01*
X594622Y-287426D01*
X594122Y-288226D01*
X593222Y-288626D01*
X590822D01*
G01X523322Y-258959D02*
Y-266959D01*
X527322D01*
G01X535122D02*
Y-261626D01*
G01Y-262559D02*
X534722Y-262026D01*
X534122Y-261759D01*
X533422Y-261626D01*
X532722Y-261892D01*
X532122Y-262426D01*
X531722Y-263226D01*
X531522Y-264292D01*
X531722Y-265359D01*
X532122Y-266159D01*
X532722Y-266692D01*
X533422Y-266959D01*
X534122Y-266826D01*
X534722Y-266426D01*
X535122Y-265893D01*
G01X539222Y-269359D02*
X539822Y-269626D01*
X540622Y-269359D01*
X541122Y-268826D01*
X541522Y-268159D01*
X542122Y-266026D01*
X543422Y-261626D01*
G01X540222D02*
X542122Y-266026D01*
G01X547822Y-263359D02*
X551022D01*
X550722Y-262426D01*
X550222Y-261892D01*
X549522Y-261626D01*
X548822Y-261759D01*
X548222Y-262159D01*
X547822Y-263092D01*
X547622Y-263893D01*
Y-264692D01*
X547822Y-265492D01*
X548322Y-266292D01*
X548922Y-266826D01*
X549622Y-266959D01*
X550322Y-266692D01*
X551022Y-265893D01*
G01X555922Y-266959D02*
Y-261626D01*
G01Y-262692D02*
X556422Y-262159D01*
X556922Y-261759D01*
X557622Y-261626D01*
X558122Y-261759D01*
X558722Y-262159D01*
G01X542022Y-316959D02*
Y-308959D01*
X546622Y-316959D01*
Y-308959D01*
G01X552322Y-311626D02*
Y-316959D01*
G01Y-309492D02*
X552122Y-309359D01*
Y-309092D01*
X552322Y-308959D01*
X552522Y-309092D01*
Y-309359D01*
X552322Y-309492D01*
G01X558622Y-316959D02*
Y-311626D01*
G01Y-312959D02*
X559022Y-312292D01*
X559622Y-311759D01*
X560422Y-311626D01*
X561122Y-311759D01*
X561722Y-312292D01*
X562022Y-313226D01*
Y-316959D01*
G01X570122D02*
Y-311626D01*
G01Y-312559D02*
X569722Y-312026D01*
X569122Y-311759D01*
X568422Y-311626D01*
X567722Y-311892D01*
X567122Y-312426D01*
X566722Y-313226D01*
X566522Y-314292D01*
X566722Y-315359D01*
X567122Y-316159D01*
X567722Y-316692D01*
X568422Y-316959D01*
X569122Y-316826D01*
X569722Y-316426D01*
X570122Y-315893D01*
G01X649922Y-310292D02*
X650522Y-309492D01*
X651222Y-309092D01*
X652022Y-308959D01*
X653022Y-309226D01*
X653722Y-309892D01*
X653922Y-310692D01*
X653822Y-311493D01*
X653422Y-312159D01*
X651422Y-313492D01*
X650522Y-314426D01*
X649922Y-315759D01*
X649722Y-316959D01*
X653922D01*
G01X659822Y-308959D02*
X659022Y-309226D01*
X658422Y-309892D01*
X658022Y-310692D01*
X657722Y-311759D01*
X657622Y-312959D01*
X657722Y-314159D01*
X658022Y-315226D01*
X658422Y-316026D01*
X659022Y-316692D01*
X659822Y-316959D01*
X660622Y-316692D01*
X661222Y-316026D01*
X661622Y-315226D01*
X661922Y-314159D01*
X662022Y-312959D01*
X661922Y-311759D01*
X661622Y-310692D01*
X661222Y-309892D01*
X660622Y-309226D01*
X659822Y-308959D01*
G01X665922Y-310292D02*
X666522Y-309492D01*
X667222Y-309092D01*
X668022Y-308959D01*
X669022Y-309226D01*
X669722Y-309892D01*
X669922Y-310692D01*
X669822Y-311493D01*
X669422Y-312159D01*
X667422Y-313492D01*
X666522Y-314426D01*
X665922Y-315759D01*
X665722Y-316959D01*
X669922D01*
G01X673922Y-310292D02*
X674522Y-309492D01*
X675222Y-309092D01*
X676022Y-308959D01*
X677022Y-309226D01*
X677722Y-309892D01*
X677922Y-310692D01*
X677822Y-311493D01*
X677422Y-312159D01*
X675422Y-313492D01*
X674522Y-314426D01*
X673922Y-315759D01*
X673722Y-316959D01*
X677922D01*
G01X682022Y-317226D02*
X685622Y-308959D01*
G01X691822Y-316959D02*
Y-308959D01*
X690622Y-310559D01*
G01Y-316959D02*
X693022D01*
G01X697922Y-310292D02*
X698522Y-309492D01*
X699222Y-309092D01*
X700022Y-308959D01*
X701022Y-309226D01*
X701722Y-309892D01*
X701922Y-310692D01*
X701822Y-311493D01*
X701422Y-312159D01*
X699422Y-313492D01*
X698522Y-314426D01*
X697922Y-315759D01*
X697722Y-316959D01*
X701922D01*
G01X706022Y-317226D02*
X709622Y-308959D01*
G01X715822D02*
X715022Y-309226D01*
X714422Y-309892D01*
X714022Y-310692D01*
X713722Y-311759D01*
X713622Y-312959D01*
X713722Y-314159D01*
X714022Y-315226D01*
X714422Y-316026D01*
X715022Y-316692D01*
X715822Y-316959D01*
X716622Y-316692D01*
X717222Y-316026D01*
X717622Y-315226D01*
X717922Y-314159D01*
X718022Y-312959D01*
X717922Y-311759D01*
X717622Y-310692D01*
X717222Y-309892D01*
X716622Y-309226D01*
X715822Y-308959D01*
G01X722122Y-316026D02*
X722822Y-316692D01*
X723622Y-316959D01*
X724422Y-316692D01*
X725122Y-315893D01*
X725622Y-314692D01*
X725822Y-313492D01*
Y-312026D01*
X725622Y-310826D01*
X725122Y-309759D01*
X724522Y-309226D01*
X723822Y-308959D01*
X723022Y-309226D01*
X722422Y-309759D01*
X722022Y-310559D01*
X721822Y-311626D01*
X722022Y-312559D01*
X722522Y-313492D01*
X723122Y-314026D01*
X723822Y-314159D01*
X724622Y-313893D01*
X725222Y-313226D01*
X725822Y-312026D01*
G01X649622Y-291959D02*
Y-283959D01*
X651622D01*
X652422Y-284359D01*
X653022Y-284892D01*
X653522Y-285692D01*
X653922Y-286626D01*
X654022Y-287959D01*
X653922Y-289292D01*
X653522Y-290226D01*
X653022Y-291026D01*
X652422Y-291559D01*
X651622Y-291959D01*
X649622D01*
G01X657322D02*
X659822Y-283959D01*
X662322Y-291959D01*
G01X661422Y-289159D02*
X658222D01*
G01X667822Y-283959D02*
X667022Y-284226D01*
X666422Y-284892D01*
X666022Y-285692D01*
X665722Y-286759D01*
X665622Y-287959D01*
X665722Y-289159D01*
X666022Y-290226D01*
X666422Y-291026D01*
X667022Y-291692D01*
X667822Y-291959D01*
X668622Y-291692D01*
X669222Y-291026D01*
X669622Y-290226D01*
X669922Y-289159D01*
X670022Y-287959D01*
X669922Y-286759D01*
X669622Y-285692D01*
X669222Y-284892D01*
X668622Y-284226D01*
X667822Y-283959D01*
G01X673922Y-291959D02*
Y-283959D01*
X677722D01*
G01X676322Y-287826D02*
X673922D01*
G01X683822Y-283959D02*
X683022Y-284226D01*
X682422Y-284892D01*
X682022Y-285692D01*
X681722Y-286759D01*
X681622Y-287959D01*
X681722Y-289159D01*
X682022Y-290226D01*
X682422Y-291026D01*
X683022Y-291692D01*
X683822Y-291959D01*
X684622Y-291692D01*
X685222Y-291026D01*
X685622Y-290226D01*
X685922Y-289159D01*
X686022Y-287959D01*
X685922Y-286759D01*
X685622Y-285692D01*
X685222Y-284892D01*
X684622Y-284226D01*
X683822Y-283959D01*
G01X691822D02*
Y-291959D01*
G01X689522Y-283959D02*
X694122D01*
G01X697922Y-291959D02*
Y-283959D01*
X701722D01*
G01X700322Y-287826D02*
X697922D01*
G01X708622Y-287692D02*
X709022Y-287292D01*
X709322Y-286626D01*
X709522Y-285692D01*
X709322Y-284892D01*
X708922Y-284359D01*
X708222Y-283959D01*
X705522D01*
Y-291959D01*
X708822D01*
X709522Y-291426D01*
X709922Y-290626D01*
X710122Y-289692D01*
X709922Y-288759D01*
X709322Y-287959D01*
X708622Y-287692D01*
X705522D01*
G01X713922Y-288626D02*
X714622Y-287692D01*
X715222Y-287159D01*
X716022Y-286892D01*
X716722Y-287159D01*
X717222Y-287692D01*
X717622Y-288492D01*
X717722Y-289426D01*
X717622Y-290226D01*
X717222Y-291026D01*
X716622Y-291692D01*
X715922Y-291959D01*
X715122Y-291692D01*
X714422Y-290893D01*
X714022Y-289692D01*
X713922Y-288359D01*
X714122Y-286626D01*
X714422Y-285692D01*
X714922Y-284759D01*
X715622Y-284092D01*
X716322Y-283959D01*
X717022Y-284226D01*
X717522Y-284892D01*
G01X721622Y-291959D02*
Y-283959D01*
X723622D01*
X724422Y-284359D01*
X725022Y-284892D01*
X725522Y-285692D01*
X725922Y-286626D01*
X726022Y-287959D01*
X725922Y-289292D01*
X725522Y-290226D01*
X725022Y-291026D01*
X724422Y-291559D01*
X723622Y-291959D01*
X721622D01*
G01X731822Y-283959D02*
X731022Y-284226D01*
X730422Y-284892D01*
X730022Y-285692D01*
X729722Y-286759D01*
X729622Y-287959D01*
X729722Y-289159D01*
X730022Y-290226D01*
X730422Y-291026D01*
X731022Y-291692D01*
X731822Y-291959D01*
X732622Y-291692D01*
X733222Y-291026D01*
X733622Y-290226D01*
X733922Y-289159D01*
X734022Y-287959D01*
X733922Y-286759D01*
X733622Y-285692D01*
X733222Y-284892D01*
X732622Y-284226D01*
X731822Y-283959D01*
G01X649862Y-270000D02*
Y-263700D01*
X652838D01*
G01X651742Y-266745D02*
X649862D01*
G01X657650Y-263700D02*
X657023Y-263910D01*
X656553Y-264435D01*
X656240Y-265065D01*
X656005Y-265905D01*
X655927Y-266850D01*
X656005Y-267795D01*
X656240Y-268635D01*
X656553Y-269265D01*
X657023Y-269790D01*
X657650Y-270000D01*
X658277Y-269790D01*
X658747Y-269265D01*
X659060Y-268635D01*
X659295Y-267795D01*
X659373Y-266850D01*
X659295Y-265905D01*
X659060Y-265065D01*
X658747Y-264435D01*
X658277Y-263910D01*
X657650Y-263700D01*
G01X663950D02*
Y-270000D01*
G01X662148Y-263700D02*
X665752D01*
G01X667900Y-272100D02*
X672600D01*
G01X674983Y-270000D02*
Y-263700D01*
X676863D01*
X677490Y-264015D01*
X677960Y-264750D01*
X678117Y-265590D01*
X677960Y-266430D01*
X677568Y-267060D01*
X676863Y-267375D01*
X674983D01*
G01X684573Y-264225D02*
X684103Y-263910D01*
X683555Y-263700D01*
X682928D01*
X682223Y-264015D01*
X681675Y-264540D01*
X681283Y-265170D01*
X680970Y-266220D01*
X680892Y-267165D01*
X681048Y-268110D01*
X681283Y-268740D01*
X681753Y-269370D01*
X682302Y-269790D01*
X682850Y-270000D01*
X683398D01*
X683947Y-269790D01*
X684417Y-269475D01*
X684808Y-269055D01*
G01X689777Y-266640D02*
X690090Y-266325D01*
X690325Y-265800D01*
X690482Y-265065D01*
X690325Y-264435D01*
X690012Y-264015D01*
X689463Y-263700D01*
X687348D01*
Y-270000D01*
X689933D01*
X690482Y-269580D01*
X690795Y-268950D01*
X690952Y-268215D01*
X690795Y-267480D01*
X690325Y-266850D01*
X689777Y-266640D01*
X687348D01*
G01X693100Y-272100D02*
X697800D01*
G01X700262Y-270000D02*
Y-263700D01*
X703238D01*
G01X702142Y-266745D02*
X700262D01*
G01X706092Y-270000D02*
X708050Y-263700D01*
X710008Y-270000D01*
G01X709303Y-267795D02*
X706797D01*
G01X712548Y-270000D02*
Y-263700D01*
X716152Y-270000D01*
Y-263700D01*
G01X718300Y-272100D02*
X723000D01*
G01X727577Y-266640D02*
X727890Y-266325D01*
X728125Y-265800D01*
X728282Y-265065D01*
X728125Y-264435D01*
X727812Y-264015D01*
X727263Y-263700D01*
X725148D01*
Y-270000D01*
X727733D01*
X728282Y-269580D01*
X728595Y-268950D01*
X728752Y-268215D01*
X728595Y-267480D01*
X728125Y-266850D01*
X727577Y-266640D01*
X725148D01*
G01X733250Y-270000D02*
X732623Y-269895D01*
X732075Y-269475D01*
X731605Y-268845D01*
X731292Y-268110D01*
X731135Y-267270D01*
Y-266430D01*
X731292Y-265590D01*
X731605Y-264855D01*
X732075Y-264225D01*
X732623Y-263805D01*
X733250Y-263700D01*
X733877Y-263805D01*
X734425Y-264225D01*
X734895Y-264855D01*
X735208Y-265590D01*
X735365Y-266430D01*
Y-267270D01*
X735208Y-268110D01*
X734895Y-268845D01*
X734425Y-269475D01*
X733877Y-269895D01*
X733250Y-270000D01*
G01X737592D02*
X739550Y-263700D01*
X741508Y-270000D01*
G01X740803Y-267795D02*
X738297D01*
G01X744283Y-270000D02*
Y-263700D01*
X746242D01*
X746868Y-264015D01*
X747260Y-264435D01*
X747417Y-265275D01*
X747260Y-266115D01*
X746790Y-266640D01*
X746242Y-266955D01*
X744283D01*
G01X746242D02*
X747417Y-270000D01*
G01X750427D02*
Y-263700D01*
X751993D01*
X752620Y-264015D01*
X753090Y-264435D01*
X753482Y-265065D01*
X753795Y-265800D01*
X753873Y-266850D01*
X753795Y-267900D01*
X753482Y-268635D01*
X753090Y-269265D01*
X752620Y-269685D01*
X751993Y-270000D01*
X750427D01*
G01X756100Y-272100D02*
X760800D01*
G01X762713Y-270000D02*
Y-263700D01*
X764750Y-268950D01*
X766787Y-263700D01*
Y-270000D01*
G01X769483D02*
Y-263700D01*
X771363D01*
X771990Y-264015D01*
X772460Y-264750D01*
X772617Y-265590D01*
X772460Y-266430D01*
X772068Y-267060D01*
X771363Y-267375D01*
X769483D01*
G01X775627Y-269055D02*
X776097Y-269580D01*
X776645Y-269895D01*
X777350Y-270000D01*
X778055Y-269790D01*
X778603Y-269370D01*
X778995Y-268635D01*
X779073Y-267795D01*
X778917Y-266955D01*
X778525Y-266430D01*
X777977Y-266010D01*
X777428Y-265905D01*
X776880Y-266010D01*
X776175Y-266430D01*
X776410Y-263700D01*
X778525D01*
G01X783650D02*
X783023Y-263910D01*
X782553Y-264435D01*
X782240Y-265065D01*
X782005Y-265905D01*
X781927Y-266850D01*
X782005Y-267795D01*
X782240Y-268635D01*
X782553Y-269265D01*
X783023Y-269790D01*
X783650Y-270000D01*
X784277Y-269790D01*
X784747Y-269265D01*
X785060Y-268635D01*
X785295Y-267795D01*
X785373Y-266850D01*
X785295Y-265905D01*
X785060Y-265065D01*
X784747Y-264435D01*
X784277Y-263910D01*
X783650Y-263700D01*
G01X790890Y-270000D02*
Y-263700D01*
X787992Y-268215D01*
X791908D01*
G01X796250Y-270000D02*
X796798Y-269895D01*
X797425Y-269580D01*
X797817Y-269055D01*
X797973Y-268320D01*
X797817Y-267585D01*
X797347Y-266955D01*
X796642Y-266640D01*
X795858D01*
X795388Y-266430D01*
X794997Y-265905D01*
X794840Y-265170D01*
X795075Y-264435D01*
X795623Y-263910D01*
X796250Y-263700D01*
X796877Y-263910D01*
X797425Y-264435D01*
X797660Y-265170D01*
X797503Y-265905D01*
X797112Y-266430D01*
X796642Y-266640D01*
X795858D01*
X795153Y-266955D01*
X794683Y-267585D01*
X794527Y-268320D01*
X794683Y-269055D01*
X795075Y-269580D01*
X795702Y-269895D01*
X796250Y-270000D01*
G01X738322Y-319959D02*
Y-311959D01*
X737122Y-313559D01*
G01Y-319959D02*
X739522D01*
G01X744422Y-316626D02*
X745122Y-315692D01*
X745722Y-315159D01*
X746522Y-314892D01*
X747222Y-315159D01*
X747722Y-315692D01*
X748122Y-316492D01*
X748222Y-317426D01*
X748122Y-318226D01*
X747722Y-319026D01*
X747122Y-319692D01*
X746422Y-319959D01*
X745622Y-319692D01*
X744922Y-318893D01*
X744522Y-317692D01*
X744422Y-316359D01*
X744622Y-314626D01*
X744922Y-313692D01*
X745422Y-312759D01*
X746122Y-312092D01*
X746822Y-311959D01*
X747522Y-312226D01*
X748022Y-312892D01*
G01X754322Y-320226D02*
X754122Y-320092D01*
Y-319826D01*
X754322Y-319692D01*
X754522Y-319826D01*
Y-320092D01*
X754322Y-320226D01*
G01X760422Y-316626D02*
X761122Y-315692D01*
X761722Y-315159D01*
X762522Y-314892D01*
X763222Y-315159D01*
X763722Y-315692D01*
X764122Y-316492D01*
X764222Y-317426D01*
X764122Y-318226D01*
X763722Y-319026D01*
X763122Y-319692D01*
X762422Y-319959D01*
X761622Y-319692D01*
X760922Y-318893D01*
X760522Y-317692D01*
X760422Y-316359D01*
X760622Y-314626D01*
X760922Y-313692D01*
X761422Y-312759D01*
X762122Y-312092D01*
X762822Y-311959D01*
X763522Y-312226D01*
X764022Y-312892D01*
G01X783322Y-319959D02*
Y-311959D01*
X782122Y-313559D01*
G01Y-319959D02*
X784522D01*
G01X791122D02*
X791322Y-318226D01*
X791622Y-316759D01*
X792022Y-315426D01*
X792522Y-313959D01*
X793322Y-311959D01*
X789322D01*
G01X799322Y-320226D02*
X799122Y-320092D01*
Y-319826D01*
X799322Y-319692D01*
X799522Y-319826D01*
Y-320092D01*
X799322Y-320226D01*
G01X805422Y-313292D02*
X806022Y-312492D01*
X806722Y-312092D01*
X807522Y-311959D01*
X808522Y-312226D01*
X809222Y-312892D01*
X809422Y-313692D01*
X809322Y-314493D01*
X808922Y-315159D01*
X806922Y-316492D01*
X806022Y-317426D01*
X805422Y-318759D01*
X805222Y-319959D01*
X809422D01*
G01X803122Y-294959D02*
Y-286959D01*
X805122D01*
X805922Y-287359D01*
X806522Y-287892D01*
X807022Y-288692D01*
X807422Y-289626D01*
X807522Y-290959D01*
X807422Y-292292D01*
X807022Y-293226D01*
X806522Y-294026D01*
X805922Y-294559D01*
X805122Y-294959D01*
X803122D01*
G01X881428Y1269383D02*
X878328D01*
Y1270303D01*
X878483Y1270610D01*
X878845Y1270840D01*
X879258Y1270917D01*
X879671Y1270840D01*
X879981Y1270648D01*
X880136Y1270303D01*
Y1269383D01*
G01X881531Y1272560D02*
X878328Y1273940D01*
G01X881428Y1275468D02*
X878328D01*
X881428Y1277232D01*
X878328D01*
G01X881531Y1279450D02*
X881480Y1279373D01*
X881376D01*
X881325Y1279450D01*
X881376Y1279527D01*
X881480D01*
X881531Y1279450D01*
G01X880136D02*
X880085Y1279373D01*
X879981D01*
X879930Y1279450D01*
X879981Y1279527D01*
X880085D01*
X880136Y1279450D01*
G01X881428Y1281707D02*
X878328D01*
Y1282473D01*
X878483Y1282780D01*
X878690Y1283010D01*
X879000Y1283202D01*
X879361Y1283355D01*
X879878Y1283393D01*
X880395Y1283355D01*
X880756Y1283202D01*
X881066Y1283010D01*
X881273Y1282780D01*
X881428Y1282473D01*
Y1281707D01*
G01Y1284692D02*
X878328Y1285650D01*
X881428Y1286608D01*
G01X880343Y1286263D02*
Y1285037D01*
G01X878328Y1288750D02*
X878431Y1288443D01*
X878690Y1288213D01*
X879000Y1288060D01*
X879413Y1287945D01*
X879878Y1287907D01*
X880343Y1287945D01*
X880756Y1288060D01*
X881066Y1288213D01*
X881325Y1288443D01*
X881428Y1288750D01*
X881325Y1289057D01*
X881066Y1289287D01*
X880756Y1289440D01*
X880343Y1289555D01*
X879878Y1289593D01*
X879413Y1289555D01*
X879000Y1289440D01*
X878690Y1289287D01*
X878431Y1289057D01*
X878328Y1288750D01*
G01X881428Y1291122D02*
X878328D01*
Y1292578D01*
G01X879826Y1292042D02*
Y1291122D01*
G01X878328Y1294950D02*
X878431Y1294643D01*
X878690Y1294413D01*
X879000Y1294260D01*
X879413Y1294145D01*
X879878Y1294107D01*
X880343Y1294145D01*
X880756Y1294260D01*
X881066Y1294413D01*
X881325Y1294643D01*
X881428Y1294950D01*
X881325Y1295257D01*
X881066Y1295487D01*
X880756Y1295640D01*
X880343Y1295755D01*
X879878Y1295793D01*
X879413Y1295755D01*
X879000Y1295640D01*
X878690Y1295487D01*
X878431Y1295257D01*
X878328Y1294950D01*
G01Y1298050D02*
X881428D01*
G01X878328Y1297168D02*
Y1298932D01*
G01X881428Y1300422D02*
X878328D01*
Y1301878D01*
G01X879826Y1301342D02*
Y1300422D01*
G01X879775Y1304557D02*
X879620Y1304710D01*
X879361Y1304825D01*
X879000Y1304902D01*
X878690Y1304825D01*
X878483Y1304672D01*
X878328Y1304403D01*
Y1303368D01*
X881428D01*
Y1304633D01*
X881221Y1304902D01*
X880911Y1305055D01*
X880550Y1305132D01*
X880188Y1305055D01*
X879878Y1304825D01*
X879775Y1304557D01*
Y1303368D01*
G01X880136Y1306622D02*
X879775Y1306890D01*
X879568Y1307120D01*
X879465Y1307427D01*
X879568Y1307695D01*
X879775Y1307887D01*
X880085Y1308040D01*
X880446Y1308078D01*
X880756Y1308040D01*
X881066Y1307887D01*
X881325Y1307657D01*
X881428Y1307388D01*
X881325Y1307082D01*
X881015Y1306813D01*
X880550Y1306660D01*
X880033Y1306622D01*
X879361Y1306698D01*
X879000Y1306813D01*
X878638Y1307005D01*
X878380Y1307273D01*
X878328Y1307542D01*
X878431Y1307810D01*
X878690Y1308002D01*
G01X881428Y1309607D02*
X878328D01*
Y1310373D01*
X878483Y1310680D01*
X878690Y1310910D01*
X879000Y1311102D01*
X879361Y1311255D01*
X879878Y1311293D01*
X880395Y1311255D01*
X880756Y1311102D01*
X881066Y1310910D01*
X881273Y1310680D01*
X881428Y1310373D01*
Y1309607D01*
G01X878328Y1313550D02*
X878431Y1313243D01*
X878690Y1313013D01*
X879000Y1312860D01*
X879413Y1312745D01*
X879878Y1312707D01*
X880343Y1312745D01*
X880756Y1312860D01*
X881066Y1313013D01*
X881325Y1313243D01*
X881428Y1313550D01*
X881325Y1313857D01*
X881066Y1314087D01*
X880756Y1314240D01*
X880343Y1314355D01*
X879878Y1314393D01*
X879413Y1314355D01*
X879000Y1314240D01*
X878690Y1314087D01*
X878431Y1313857D01*
X878328Y1313550D01*
M02*
